FILE_TYPE = MACRO_DRAWING;
SET COLOR_WIRE YELLOW;
SET COLOR_PROP ORANGE;
SET COLOR_DOT WHITE;
SET COLOR_ARC YELLOW;
SET COLOR_BODY GREEN;
SET COLOR_NOTE PURPLE;
SET PROP_DISPLAY VALUE;
SET PAGE_NUMBER P136;
FORCEADD Q_RES..1
R 2
(-6075 5725);
FORCEPROP 1 LAST LOCATION R427
J 2
(-6175 5725);
DISPLAY 0.489362 (-6175 5725);
PAINT SKYBLUE (-6175 5725);
FORCEPROP 0 LAST $SEC 1
J 2
(-5800 5775);
DISPLAY 0.680851 (-5800 5775);
PAINT MONO (-5800 5775);
DISPLAY INVISIBLE (-5800 5775);
FORCEPROP 0 LAST CDS_SEC 1
J 2
(-5800 5775);
DISPLAY 1.021277 (-5800 5775);
DISPLAY INVISIBLE (-5800 5775);
FORCEPROP 1 LASTPIN (-5975 5725) $PN 1
J 2
(-5987 5737);
DISPLAY 0.489362 (-5987 5737);
PAINT MONO (-5987 5737);
FORCEPROP 1 LASTPIN (-6175 5725) $PN 2
J 2
(-6137 5737);
DISPLAY 0.489362 (-6137 5737);
PAINT MONO (-6137 5737);
FORCEPROP 1 LAST VALUE 0
J 0
(-5975 5725);
DISPLAY 0.489362 (-5975 5725);
PAINT SKYBLUE (-5975 5725);
FORCEPROP 2 LAST CDS_LIB pure_quanta
J 2
(-6075 5725);
DISPLAY INVISIBLE (-6075 5725);
FORCEPROP 1 LAST WATTAGE 1/16W
J 0
(-6475 5650);
DISPLAY 0.489362 (-6475 5650);
PAINT SKYBLUE (-6475 5650);
DISPLAY INVISIBLE (-6475 5650);
FORCEPROP 1 LAST MATERIAL CHIP
J 2
(-6500 5650);
DISPLAY 0.489362 (-6500 5650);
PAINT SKYBLUE (-6500 5650);
DISPLAY INVISIBLE (-6500 5650);
FORCEPROP 1 LAST TOLERANCE 5%
J 2
(-6050 5650);
DISPLAY 0.489362 (-6050 5650);
PAINT SKYBLUE (-6050 5650);
DISPLAY INVISIBLE (-6050 5650);
FORCEPROP 1 LAST PACK_TYPE 0402LF
J 2
(-6125 5650);
DISPLAY 0.489362 (-6125 5650);
PAINT SKYBLUE (-6125 5650);
DISPLAY INVISIBLE (-6125 5650);
FORCEPROP 1 LAST PATH I100
J 2
(-6025 5875);
DISPLAY 0.978723 (-6025 5875);
PAINT WHITE (-6025 5875);
DISPLAY INVISIBLE (-6025 5875);
FORCEPROP 1 LAST PART_NUMBER CS00002JB13
J 2
(-6100 5775);
DISPLAY 0.489362 (-6100 5775);
PAINT SKYBLUE (-6100 5775);
DISPLAY INVISIBLE (-6100 5775);
FORCEADD OFFPAGE..1
(-7125 5775);
FORCEPROP 2 LAST $XR0 28 
J 0
(-7376 5775);
DISPLAY 0.638298 (-7376 5775);
PAINT MONO (-7376 5775);
FORCEPROP 2 LAST CDS_LIB standard
J 0
(-7125 5775);
DISPLAY INVISIBLE (-7125 5775);
FORCEPROP 1 LAST OFFPAGE TRUE
J 0
(-6800 5650);
DISPLAY 0.872340 (-6800 5650);
PAINT GREEN (-6800 5650);
DISPLAY INVISIBLE (-6800 5650);
FORCEPROP 1 LAST COMMENT_BODY TRUE
J 0
(-7000 5675);
DISPLAY 0.872340 (-7000 5675);
PAINT GREEN (-7000 5675);
DISPLAY INVISIBLE (-7000 5675);
FORCEPROP 2 LAST PATH I101
J 0
(-7075 5850);
DISPLAY 1.021277 (-7075 5850);
DISPLAY INVISIBLE (-7075 5850);
FORCEADD OFFPAGE..3
R 2
(-7125 5725);
FORCEPROP 2 LAST $XR0 28 
J 0
(-7404 5725);
DISPLAY 0.638298 (-7404 5725);
PAINT MONO (-7404 5725);
FORCEPROP 2 LAST CDS_LIB standard
J 0
(-7125 5725);
DISPLAY INVISIBLE (-7125 5725);
FORCEPROP 1 LAST OFFPAGE TRUE
J 2
(-7450 5600);
DISPLAY 0.872340 (-7450 5600);
PAINT GREEN (-7450 5600);
DISPLAY INVISIBLE (-7450 5600);
FORCEPROP 1 LAST COMMENT_BODY TRUE
J 2
(-7075 5625);
DISPLAY 0.872340 (-7075 5625);
PAINT GREEN (-7075 5625);
DISPLAY INVISIBLE (-7075 5625);
FORCEPROP 2 LAST PATH I102
J 0
(-7075 5800);
DISPLAY 1.021277 (-7075 5800);
DISPLAY INVISIBLE (-7075 5800);
FORCEADD Q_RES..1
R 2
(-6050 4375);
FORCEPROP 1 LAST LOCATION R428
J 2
(-6150 4375);
DISPLAY 0.489362 (-6150 4375);
PAINT SKYBLUE (-6150 4375);
FORCEPROP 0 LAST $SEC 1
J 2
(-5775 4425);
DISPLAY 0.680851 (-5775 4425);
PAINT MONO (-5775 4425);
DISPLAY INVISIBLE (-5775 4425);
FORCEPROP 0 LAST CDS_SEC 1
J 2
(-5775 4425);
DISPLAY 1.021277 (-5775 4425);
DISPLAY INVISIBLE (-5775 4425);
FORCEPROP 1 LASTPIN (-5950 4375) $PN 1
J 2
(-5962 4387);
DISPLAY 0.489362 (-5962 4387);
PAINT MONO (-5962 4387);
FORCEPROP 1 LASTPIN (-6150 4375) $PN 2
J 2
(-6112 4387);
DISPLAY 0.489362 (-6112 4387);
PAINT MONO (-6112 4387);
FORCEPROP 1 LAST VALUE 0
J 0
(-5950 4375);
DISPLAY 0.489362 (-5950 4375);
PAINT SKYBLUE (-5950 4375);
FORCEPROP 2 LAST CDS_LIB pure_quanta
J 2
(-6050 4375);
DISPLAY INVISIBLE (-6050 4375);
FORCEPROP 1 LAST WATTAGE 1/16W
J 0
(-6450 4300);
DISPLAY 0.489362 (-6450 4300);
PAINT SKYBLUE (-6450 4300);
DISPLAY INVISIBLE (-6450 4300);
FORCEPROP 1 LAST MATERIAL CHIP
J 2
(-6475 4300);
DISPLAY 0.489362 (-6475 4300);
PAINT SKYBLUE (-6475 4300);
DISPLAY INVISIBLE (-6475 4300);
FORCEPROP 1 LAST TOLERANCE 5%
J 2
(-6025 4300);
DISPLAY 0.489362 (-6025 4300);
PAINT SKYBLUE (-6025 4300);
DISPLAY INVISIBLE (-6025 4300);
FORCEPROP 1 LAST PACK_TYPE 0402LF
J 2
(-6100 4300);
DISPLAY 0.489362 (-6100 4300);
PAINT SKYBLUE (-6100 4300);
DISPLAY INVISIBLE (-6100 4300);
FORCEPROP 1 LAST PATH I103
J 2
(-6000 4525);
DISPLAY 0.978723 (-6000 4525);
PAINT WHITE (-6000 4525);
DISPLAY INVISIBLE (-6000 4525);
FORCEPROP 1 LAST PART_NUMBER CS00002JB13
J 2
(-6075 4425);
DISPLAY 0.489362 (-6075 4425);
PAINT SKYBLUE (-6075 4425);
DISPLAY INVISIBLE (-6075 4425);
FORCEADD Q_RES..1
R 2
(-6050 4325);
FORCEPROP 1 LAST LOCATION R429
J 2
(-6150 4325);
DISPLAY 0.489362 (-6150 4325);
PAINT SKYBLUE (-6150 4325);
FORCEPROP 0 LAST $SEC 1
J 2
(-5775 4375);
DISPLAY 0.680851 (-5775 4375);
PAINT MONO (-5775 4375);
DISPLAY INVISIBLE (-5775 4375);
FORCEPROP 0 LAST CDS_SEC 1
J 2
(-5775 4375);
DISPLAY 1.021277 (-5775 4375);
DISPLAY INVISIBLE (-5775 4375);
FORCEPROP 1 LASTPIN (-5950 4325) $PN 1
J 2
(-5962 4337);
DISPLAY 0.489362 (-5962 4337);
PAINT MONO (-5962 4337);
FORCEPROP 1 LASTPIN (-6150 4325) $PN 2
J 2
(-6112 4337);
DISPLAY 0.489362 (-6112 4337);
PAINT MONO (-6112 4337);
FORCEPROP 1 LAST VALUE 0
J 0
(-5950 4325);
DISPLAY 0.489362 (-5950 4325);
PAINT SKYBLUE (-5950 4325);
FORCEPROP 2 LAST CDS_LIB pure_quanta
J 2
(-6050 4325);
DISPLAY INVISIBLE (-6050 4325);
FORCEPROP 1 LAST WATTAGE 1/16W
J 0
(-6450 4250);
DISPLAY 0.489362 (-6450 4250);
PAINT SKYBLUE (-6450 4250);
DISPLAY INVISIBLE (-6450 4250);
FORCEPROP 1 LAST MATERIAL CHIP
J 2
(-6475 4250);
DISPLAY 0.489362 (-6475 4250);
PAINT SKYBLUE (-6475 4250);
DISPLAY INVISIBLE (-6475 4250);
FORCEPROP 1 LAST TOLERANCE 5%
J 2
(-6025 4250);
DISPLAY 0.489362 (-6025 4250);
PAINT SKYBLUE (-6025 4250);
DISPLAY INVISIBLE (-6025 4250);
FORCEPROP 1 LAST PACK_TYPE 0402LF
J 2
(-6100 4250);
DISPLAY 0.489362 (-6100 4250);
PAINT SKYBLUE (-6100 4250);
DISPLAY INVISIBLE (-6100 4250);
FORCEPROP 1 LAST PATH I104
J 2
(-6000 4475);
DISPLAY 0.978723 (-6000 4475);
PAINT WHITE (-6000 4475);
DISPLAY INVISIBLE (-6000 4475);
FORCEPROP 1 LAST PART_NUMBER CS00002JB13
J 2
(-6075 4375);
DISPLAY 0.489362 (-6075 4375);
PAINT SKYBLUE (-6075 4375);
DISPLAY INVISIBLE (-6075 4375);
FORCEADD OFFPAGE..3
R 2
(-7100 4325);
FORCEPROP 2 LAST $XR0 28 
J 0
(-7349 4325);
DISPLAY 0.638298 (-7349 4325);
PAINT MONO (-7349 4325);
FORCEPROP 2 LAST CDS_LIB standard
J 0
(-7100 4325);
DISPLAY INVISIBLE (-7100 4325);
FORCEPROP 1 LAST OFFPAGE TRUE
J 2
(-7425 4200);
DISPLAY 0.872340 (-7425 4200);
PAINT GREEN (-7425 4200);
DISPLAY INVISIBLE (-7425 4200);
FORCEPROP 1 LAST COMMENT_BODY TRUE
J 2
(-7050 4225);
DISPLAY 0.872340 (-7050 4225);
PAINT GREEN (-7050 4225);
DISPLAY INVISIBLE (-7050 4225);
FORCEPROP 2 LAST PATH I105
J 0
(-7050 4400);
DISPLAY 1.021277 (-7050 4400);
DISPLAY INVISIBLE (-7050 4400);
FORCEADD OFFPAGE..1
(-7100 4375);
FORCEPROP 2 LAST $XR0 28 
J 0
(-7321 4375);
DISPLAY 0.638298 (-7321 4375);
PAINT MONO (-7321 4375);
FORCEPROP 2 LAST CDS_LIB standard
J 0
(-7100 4375);
DISPLAY INVISIBLE (-7100 4375);
FORCEPROP 1 LAST OFFPAGE TRUE
J 0
(-6775 4250);
DISPLAY 0.872340 (-6775 4250);
PAINT GREEN (-6775 4250);
DISPLAY INVISIBLE (-6775 4250);
FORCEPROP 1 LAST COMMENT_BODY TRUE
J 0
(-6975 4275);
DISPLAY 0.872340 (-6975 4275);
PAINT GREEN (-6975 4275);
DISPLAY INVISIBLE (-6975 4275);
FORCEPROP 2 LAST PATH I106
J 0
(-7050 4450);
DISPLAY 1.021277 (-7050 4450);
DISPLAY INVISIBLE (-7050 4450);
FORCEADD Q_RES..1
R 2
(-6050 2800);
FORCEPROP 1 LAST LOCATION R565
J 2
(-6150 2800);
DISPLAY 0.489362 (-6150 2800);
PAINT SKYBLUE (-6150 2800);
FORCEPROP 0 LAST $SEC 1
J 2
(-5775 2850);
DISPLAY 0.680851 (-5775 2850);
PAINT MONO (-5775 2850);
DISPLAY INVISIBLE (-5775 2850);
FORCEPROP 0 LAST CDS_SEC 1
J 2
(-5775 2850);
DISPLAY 1.021277 (-5775 2850);
DISPLAY INVISIBLE (-5775 2850);
FORCEPROP 1 LASTPIN (-5950 2800) $PN 1
J 2
(-5962 2812);
DISPLAY 0.489362 (-5962 2812);
PAINT MONO (-5962 2812);
FORCEPROP 1 LASTPIN (-6150 2800) $PN 2
J 2
(-6112 2812);
DISPLAY 0.489362 (-6112 2812);
PAINT MONO (-6112 2812);
FORCEPROP 1 LAST VALUE 0
J 0
(-5950 2800);
DISPLAY 0.489362 (-5950 2800);
PAINT SKYBLUE (-5950 2800);
FORCEPROP 2 LAST CDS_LIB pure_quanta
J 2
(-6050 2800);
DISPLAY INVISIBLE (-6050 2800);
FORCEPROP 1 LAST WATTAGE 1/16W
J 0
(-6450 2725);
DISPLAY 0.489362 (-6450 2725);
PAINT SKYBLUE (-6450 2725);
DISPLAY INVISIBLE (-6450 2725);
FORCEPROP 1 LAST MATERIAL CHIP
J 2
(-6475 2725);
DISPLAY 0.489362 (-6475 2725);
PAINT SKYBLUE (-6475 2725);
DISPLAY INVISIBLE (-6475 2725);
FORCEPROP 1 LAST TOLERANCE 5%
J 2
(-6025 2725);
DISPLAY 0.489362 (-6025 2725);
PAINT SKYBLUE (-6025 2725);
DISPLAY INVISIBLE (-6025 2725);
FORCEPROP 1 LAST PACK_TYPE 0402LF
J 2
(-6100 2725);
DISPLAY 0.489362 (-6100 2725);
PAINT SKYBLUE (-6100 2725);
DISPLAY INVISIBLE (-6100 2725);
FORCEPROP 1 LAST PATH I107
J 2
(-6000 2950);
DISPLAY 0.978723 (-6000 2950);
PAINT WHITE (-6000 2950);
DISPLAY INVISIBLE (-6000 2950);
FORCEPROP 1 LAST PART_NUMBER CS00002JB13
J 2
(-6075 2850);
DISPLAY 0.489362 (-6075 2850);
PAINT SKYBLUE (-6075 2850);
DISPLAY INVISIBLE (-6075 2850);
FORCEADD Q_RES..1
R 2
(-6050 2850);
FORCEPROP 1 LAST LOCATION R564
J 2
(-6150 2850);
DISPLAY 0.489362 (-6150 2850);
PAINT SKYBLUE (-6150 2850);
FORCEPROP 0 LAST $SEC 1
J 2
(-5775 2900);
DISPLAY 0.680851 (-5775 2900);
PAINT MONO (-5775 2900);
DISPLAY INVISIBLE (-5775 2900);
FORCEPROP 0 LAST CDS_SEC 1
J 2
(-5775 2900);
DISPLAY 1.021277 (-5775 2900);
DISPLAY INVISIBLE (-5775 2900);
FORCEPROP 1 LASTPIN (-5950 2850) $PN 1
J 2
(-5962 2862);
DISPLAY 0.489362 (-5962 2862);
PAINT MONO (-5962 2862);
FORCEPROP 1 LASTPIN (-6150 2850) $PN 2
J 2
(-6112 2862);
DISPLAY 0.489362 (-6112 2862);
PAINT MONO (-6112 2862);
FORCEPROP 1 LAST VALUE 0
J 0
(-5950 2850);
DISPLAY 0.489362 (-5950 2850);
PAINT SKYBLUE (-5950 2850);
FORCEPROP 2 LAST CDS_LIB pure_quanta
J 2
(-6050 2850);
DISPLAY INVISIBLE (-6050 2850);
FORCEPROP 1 LAST WATTAGE 1/16W
J 0
(-6450 2775);
DISPLAY 0.489362 (-6450 2775);
PAINT SKYBLUE (-6450 2775);
DISPLAY INVISIBLE (-6450 2775);
FORCEPROP 1 LAST MATERIAL CHIP
J 2
(-6475 2775);
DISPLAY 0.489362 (-6475 2775);
PAINT SKYBLUE (-6475 2775);
DISPLAY INVISIBLE (-6475 2775);
FORCEPROP 1 LAST TOLERANCE 5%
J 2
(-6025 2775);
DISPLAY 0.489362 (-6025 2775);
PAINT SKYBLUE (-6025 2775);
DISPLAY INVISIBLE (-6025 2775);
FORCEPROP 1 LAST PACK_TYPE 0402LF
J 2
(-6100 2775);
DISPLAY 0.489362 (-6100 2775);
PAINT SKYBLUE (-6100 2775);
DISPLAY INVISIBLE (-6100 2775);
FORCEPROP 1 LAST PATH I108
J 2
(-6000 3000);
DISPLAY 0.978723 (-6000 3000);
PAINT WHITE (-6000 3000);
DISPLAY INVISIBLE (-6000 3000);
FORCEPROP 1 LAST PART_NUMBER CS00002JB13
J 2
(-6075 2900);
DISPLAY 0.489362 (-6075 2900);
PAINT SKYBLUE (-6075 2900);
DISPLAY INVISIBLE (-6075 2900);
FORCEADD OFFPAGE..1
(-7100 2850);
FORCEPROP 2 LAST $XR0 55 
J 0
(-7321 2850);
DISPLAY 0.638298 (-7321 2850);
PAINT MONO (-7321 2850);
FORCEPROP 2 LAST CDS_LIB standard
J 0
(-7100 2850);
DISPLAY INVISIBLE (-7100 2850);
FORCEPROP 1 LAST OFFPAGE TRUE
J 0
(-6775 2725);
DISPLAY 0.872340 (-6775 2725);
PAINT GREEN (-6775 2725);
DISPLAY INVISIBLE (-6775 2725);
FORCEPROP 1 LAST COMMENT_BODY TRUE
J 0
(-6975 2750);
DISPLAY 0.872340 (-6975 2750);
PAINT GREEN (-6975 2750);
DISPLAY INVISIBLE (-6975 2750);
FORCEPROP 2 LAST PATH I109
J 0
(-7050 2925);
DISPLAY 1.021277 (-7050 2925);
DISPLAY INVISIBLE (-7050 2925);
FORCEADD OFFPAGE..3
R 2
(-7100 2800);
FORCEPROP 2 LAST $XR0 55 
J 0
(-7349 2800);
DISPLAY 0.638298 (-7349 2800);
PAINT MONO (-7349 2800);
FORCEPROP 2 LAST CDS_LIB standard
J 0
(-7100 2800);
DISPLAY INVISIBLE (-7100 2800);
FORCEPROP 1 LAST OFFPAGE TRUE
J 2
(-7425 2675);
DISPLAY 0.872340 (-7425 2675);
PAINT GREEN (-7425 2675);
DISPLAY INVISIBLE (-7425 2675);
FORCEPROP 1 LAST COMMENT_BODY TRUE
J 2
(-7050 2700);
DISPLAY 0.872340 (-7050 2700);
PAINT GREEN (-7050 2700);
DISPLAY INVISIBLE (-7050 2700);
FORCEPROP 2 LAST PATH I110
J 0
(-7050 2875);
DISPLAY 1.021277 (-7050 2875);
DISPLAY INVISIBLE (-7050 2875);
FORCEADD Q_RES..1
R 2
(-5975 1400);
FORCEPROP 1 LAST LOCATION R566
J 2
(-6075 1400);
DISPLAY 0.489362 (-6075 1400);
PAINT SKYBLUE (-6075 1400);
FORCEPROP 0 LAST $SEC 1
J 2
(-5700 1450);
DISPLAY 0.680851 (-5700 1450);
PAINT MONO (-5700 1450);
DISPLAY INVISIBLE (-5700 1450);
FORCEPROP 0 LAST CDS_SEC 1
J 2
(-5700 1450);
DISPLAY 1.021277 (-5700 1450);
DISPLAY INVISIBLE (-5700 1450);
FORCEPROP 1 LASTPIN (-5875 1400) $PN 1
J 2
(-5887 1412);
DISPLAY 0.489362 (-5887 1412);
PAINT MONO (-5887 1412);
FORCEPROP 1 LASTPIN (-6075 1400) $PN 2
J 2
(-6037 1412);
DISPLAY 0.489362 (-6037 1412);
PAINT MONO (-6037 1412);
FORCEPROP 1 LAST VALUE 0
J 0
(-5875 1400);
DISPLAY 0.489362 (-5875 1400);
PAINT SKYBLUE (-5875 1400);
FORCEPROP 2 LAST CDS_LIB pure_quanta
J 2
(-5975 1400);
DISPLAY INVISIBLE (-5975 1400);
FORCEPROP 1 LAST WATTAGE 1/16W
J 0
(-6375 1325);
DISPLAY 0.489362 (-6375 1325);
PAINT SKYBLUE (-6375 1325);
DISPLAY INVISIBLE (-6375 1325);
FORCEPROP 1 LAST MATERIAL CHIP
J 2
(-6400 1325);
DISPLAY 0.489362 (-6400 1325);
PAINT SKYBLUE (-6400 1325);
DISPLAY INVISIBLE (-6400 1325);
FORCEPROP 1 LAST TOLERANCE 5%
J 2
(-5950 1325);
DISPLAY 0.489362 (-5950 1325);
PAINT SKYBLUE (-5950 1325);
DISPLAY INVISIBLE (-5950 1325);
FORCEPROP 1 LAST PACK_TYPE 0402LF
J 2
(-6025 1325);
DISPLAY 0.489362 (-6025 1325);
PAINT SKYBLUE (-6025 1325);
DISPLAY INVISIBLE (-6025 1325);
FORCEPROP 1 LAST PATH I111
J 2
(-5925 1550);
DISPLAY 0.978723 (-5925 1550);
PAINT WHITE (-5925 1550);
DISPLAY INVISIBLE (-5925 1550);
FORCEPROP 1 LAST PART_NUMBER CS00002JB13
J 2
(-6000 1450);
DISPLAY 0.489362 (-6000 1450);
PAINT SKYBLUE (-6000 1450);
DISPLAY INVISIBLE (-6000 1450);
FORCEADD Q_RES..1
R 2
(-5975 1350);
FORCEPROP 1 LAST LOCATION R567
J 2
(-6075 1350);
DISPLAY 0.489362 (-6075 1350);
PAINT SKYBLUE (-6075 1350);
FORCEPROP 0 LAST $SEC 1
J 2
(-5700 1400);
DISPLAY 0.680851 (-5700 1400);
PAINT MONO (-5700 1400);
DISPLAY INVISIBLE (-5700 1400);
FORCEPROP 0 LAST CDS_SEC 1
J 2
(-5700 1400);
DISPLAY 1.021277 (-5700 1400);
DISPLAY INVISIBLE (-5700 1400);
FORCEPROP 1 LASTPIN (-5875 1350) $PN 1
J 2
(-5887 1362);
DISPLAY 0.489362 (-5887 1362);
PAINT MONO (-5887 1362);
FORCEPROP 1 LASTPIN (-6075 1350) $PN 2
J 2
(-6037 1362);
DISPLAY 0.489362 (-6037 1362);
PAINT MONO (-6037 1362);
FORCEPROP 1 LAST VALUE 0
J 0
(-5875 1350);
DISPLAY 0.489362 (-5875 1350);
PAINT SKYBLUE (-5875 1350);
FORCEPROP 2 LAST CDS_LIB pure_quanta
J 2
(-5975 1350);
DISPLAY INVISIBLE (-5975 1350);
FORCEPROP 1 LAST WATTAGE 1/16W
J 0
(-6375 1275);
DISPLAY 0.489362 (-6375 1275);
PAINT SKYBLUE (-6375 1275);
DISPLAY INVISIBLE (-6375 1275);
FORCEPROP 1 LAST MATERIAL CHIP
J 2
(-6400 1275);
DISPLAY 0.489362 (-6400 1275);
PAINT SKYBLUE (-6400 1275);
DISPLAY INVISIBLE (-6400 1275);
FORCEPROP 1 LAST TOLERANCE 5%
J 2
(-5950 1275);
DISPLAY 0.489362 (-5950 1275);
PAINT SKYBLUE (-5950 1275);
DISPLAY INVISIBLE (-5950 1275);
FORCEPROP 1 LAST PACK_TYPE 0402LF
J 2
(-6025 1275);
DISPLAY 0.489362 (-6025 1275);
PAINT SKYBLUE (-6025 1275);
DISPLAY INVISIBLE (-6025 1275);
FORCEPROP 1 LAST PATH I112
J 2
(-5925 1500);
DISPLAY 0.978723 (-5925 1500);
PAINT WHITE (-5925 1500);
DISPLAY INVISIBLE (-5925 1500);
FORCEPROP 1 LAST PART_NUMBER CS00002JB13
J 2
(-6000 1400);
DISPLAY 0.489362 (-6000 1400);
PAINT SKYBLUE (-6000 1400);
DISPLAY INVISIBLE (-6000 1400);
FORCEADD OFFPAGE..1
(-7025 1400);
FORCEPROP 2 LAST $XR0 55 
J 0
(-7276 1400);
DISPLAY 0.638298 (-7276 1400);
PAINT MONO (-7276 1400);
FORCEPROP 2 LAST CDS_LIB standard
J 0
(-7025 1400);
DISPLAY INVISIBLE (-7025 1400);
FORCEPROP 1 LAST OFFPAGE TRUE
J 0
(-6700 1275);
DISPLAY 0.872340 (-6700 1275);
PAINT GREEN (-6700 1275);
DISPLAY INVISIBLE (-6700 1275);
FORCEPROP 1 LAST COMMENT_BODY TRUE
J 0
(-6900 1300);
DISPLAY 0.872340 (-6900 1300);
PAINT GREEN (-6900 1300);
DISPLAY INVISIBLE (-6900 1300);
FORCEPROP 2 LAST PATH I113
J 0
(-6975 1475);
DISPLAY 1.021277 (-6975 1475);
DISPLAY INVISIBLE (-6975 1475);
FORCEADD OFFPAGE..3
R 2
(-7025 1350);
FORCEPROP 2 LAST $XR0 55 
J 0
(-7304 1350);
DISPLAY 0.638298 (-7304 1350);
PAINT MONO (-7304 1350);
FORCEPROP 2 LAST CDS_LIB standard
J 0
(-7025 1350);
DISPLAY INVISIBLE (-7025 1350);
FORCEPROP 1 LAST OFFPAGE TRUE
J 2
(-7350 1225);
DISPLAY 0.872340 (-7350 1225);
PAINT GREEN (-7350 1225);
DISPLAY INVISIBLE (-7350 1225);
FORCEPROP 1 LAST COMMENT_BODY TRUE
J 2
(-6975 1250);
DISPLAY 0.872340 (-6975 1250);
PAINT GREEN (-6975 1250);
DISPLAY INVISIBLE (-6975 1250);
FORCEPROP 2 LAST PATH I114
J 0
(-6975 1425);
DISPLAY 1.021277 (-6975 1425);
DISPLAY INVISIBLE (-6975 1425);
FORCEADD Q_RES..1
(-6100 5325);
FORCEPROP 1 LAST LOCATION R2310
J 0
(-6275 5325);
DISPLAY 0.489362 (-6275 5325);
PAINT SKYBLUE (-6275 5325);
FORCEPROP 0 LAST $SEC 1
J 0
(-5975 5350);
DISPLAY 0.680851 (-5975 5350);
PAINT MONO (-5975 5350);
DISPLAY INVISIBLE (-5975 5350);
FORCEPROP 0 LAST CDS_SEC 1
J 0
(-5975 5350);
DISPLAY 1.021277 (-5975 5350);
DISPLAY INVISIBLE (-5975 5350);
FORCEPROP 1 LASTPIN (-6200 5325) $PN 1
J 0
(-6188 5337);
DISPLAY 0.489362 (-6188 5337);
PAINT MONO (-6188 5337);
FORCEPROP 1 LASTPIN (-6000 5325) $PN 2
J 0
(-6038 5337);
DISPLAY 0.489362 (-6038 5337);
PAINT MONO (-6038 5337);
FORCEPROP 1 LAST VALUE 0
J 2
(-6000 5325);
DISPLAY 0.489362 (-6000 5325);
PAINT SKYBLUE (-6000 5325);
FORCEPROP 1 LAST MATERIAL EMPTY
J 0
(-5975 5325);
DISPLAY 0.489362 (-5975 5325);
PAINT RED (-5975 5325);
FORCEPROP 2 LAST CDS_LIB pure_quanta
J 0
(-6100 5325);
DISPLAY INVISIBLE (-6100 5325);
FORCEPROP 1 LAST WATTAGE 1/16W
J 2
(-6125 5175);
DISPLAY 0.510638 (-6125 5175);
PAINT SKYBLUE (-6125 5175);
DISPLAY INVISIBLE (-6125 5175);
FORCEPROP 1 LAST TOLERANCE 5%
J 0
(-6100 5225);
DISPLAY 0.510638 (-6100 5225);
PAINT SKYBLUE (-6100 5225);
DISPLAY INVISIBLE (-6100 5225);
FORCEPROP 1 LAST PACK_TYPE 0402LF
J 0
(-5850 5175);
DISPLAY 0.510638 (-5850 5175);
PAINT SKYBLUE (-5850 5175);
DISPLAY INVISIBLE (-5850 5175);
FORCEPROP 1 LAST PATH I123
J 0
(-6150 5475);
DISPLAY 0.978723 (-6150 5475);
PAINT WHITE (-6150 5475);
DISPLAY INVISIBLE (-6150 5475);
FORCEPROP 1 LAST PART_NUMBER CS00002JB13
J 0
(-6150 5425);
DISPLAY 0.510638 (-6150 5425);
PAINT SKYBLUE (-6150 5425);
DISPLAY INVISIBLE (-6150 5425);
FORCEADD Q_RES..1
(-6100 5275);
FORCEPROP 1 LAST LOCATION R2311
J 0
(-6275 5275);
DISPLAY 0.489362 (-6275 5275);
PAINT SKYBLUE (-6275 5275);
FORCEPROP 0 LAST $SEC 1
J 0
(-5975 5300);
DISPLAY 0.680851 (-5975 5300);
PAINT MONO (-5975 5300);
DISPLAY INVISIBLE (-5975 5300);
FORCEPROP 0 LAST CDS_SEC 1
J 0
(-5975 5300);
DISPLAY 1.021277 (-5975 5300);
DISPLAY INVISIBLE (-5975 5300);
FORCEPROP 1 LASTPIN (-6200 5275) $PN 1
J 0
(-6188 5287);
DISPLAY 0.489362 (-6188 5287);
PAINT MONO (-6188 5287);
FORCEPROP 1 LASTPIN (-6000 5275) $PN 2
J 0
(-6038 5287);
DISPLAY 0.489362 (-6038 5287);
PAINT MONO (-6038 5287);
FORCEPROP 1 LAST MATERIAL EMPTY
J 0
(-5975 5275);
DISPLAY 0.489362 (-5975 5275);
PAINT RED (-5975 5275);
FORCEPROP 1 LAST VALUE 0
J 2
(-6000 5275);
DISPLAY 0.489362 (-6000 5275);
PAINT SKYBLUE (-6000 5275);
FORCEPROP 2 LAST CDS_LIB pure_quanta
J 0
(-6100 5275);
DISPLAY INVISIBLE (-6100 5275);
FORCEPROP 1 LAST WATTAGE 1/16W
J 2
(-6125 5125);
DISPLAY 0.510638 (-6125 5125);
PAINT SKYBLUE (-6125 5125);
DISPLAY INVISIBLE (-6125 5125);
FORCEPROP 1 LAST TOLERANCE 5%
J 0
(-6100 5175);
DISPLAY 0.510638 (-6100 5175);
PAINT SKYBLUE (-6100 5175);
DISPLAY INVISIBLE (-6100 5175);
FORCEPROP 1 LAST PACK_TYPE 0402LF
J 0
(-5850 5125);
DISPLAY 0.510638 (-5850 5125);
PAINT SKYBLUE (-5850 5125);
DISPLAY INVISIBLE (-5850 5125);
FORCEPROP 1 LAST PATH I124
J 0
(-6150 5425);
DISPLAY 0.978723 (-6150 5425);
PAINT WHITE (-6150 5425);
DISPLAY INVISIBLE (-6150 5425);
FORCEPROP 1 LAST PART_NUMBER CS00002JB13
J 0
(-6150 5375);
DISPLAY 0.510638 (-6150 5375);
PAINT SKYBLUE (-6150 5375);
DISPLAY INVISIBLE (-6150 5375);
FORCEADD Q_RES..1
(-3175 5325);
FORCEPROP 1 LAST LOCATION R1330
J 0
(-3275 5325);
DISPLAY 0.489362 (-3275 5325);
PAINT SKYBLUE (-3275 5325);
FORCEPROP 0 LAST $SEC 1
J 0
(-3275 5375);
DISPLAY 0.680851 (-3275 5375);
PAINT MONO (-3275 5375);
DISPLAY INVISIBLE (-3275 5375);
FORCEPROP 0 LAST CDS_SEC 1
J 0
(-3275 5375);
DISPLAY 0.680851 (-3275 5375);
DISPLAY INVISIBLE (-3275 5375);
FORCEPROP 1 LASTPIN (-3275 5325) $PN 1
J 0
(-3263 5337);
DISPLAY 0.489362 (-3263 5337);
PAINT MONO (-3263 5337);
FORCEPROP 1 LASTPIN (-3075 5325) $PN 2
J 0
(-3113 5337);
DISPLAY 0.489362 (-3113 5337);
PAINT MONO (-3113 5337);
FORCEPROP 1 LAST VALUE 0
J 2
(-3075 5325);
DISPLAY 0.489362 (-3075 5325);
PAINT SKYBLUE (-3075 5325);
FORCEPROP 1 LAST MATERIAL EMPTY
J 0
(-3050 5325);
DISPLAY 0.489362 (-3050 5325);
PAINT RED (-3050 5325);
FORCEPROP 2 LAST CDS_LIB pure_quanta
J 0
(-3175 5325);
DISPLAY INVISIBLE (-3175 5325);
FORCEPROP 1 LAST WATTAGE 1/16W
J 2
(-3200 5175);
DISPLAY 0.510638 (-3200 5175);
PAINT SKYBLUE (-3200 5175);
DISPLAY INVISIBLE (-3200 5175);
FORCEPROP 1 LAST TOLERANCE 5%
J 0
(-3175 5225);
DISPLAY 0.510638 (-3175 5225);
PAINT SKYBLUE (-3175 5225);
DISPLAY INVISIBLE (-3175 5225);
FORCEPROP 1 LAST PACK_TYPE 0402LF
J 0
(-2925 5175);
DISPLAY 0.510638 (-2925 5175);
PAINT SKYBLUE (-2925 5175);
DISPLAY INVISIBLE (-2925 5175);
FORCEPROP 1 LAST PATH I131
J 0
(-3225 5475);
DISPLAY 0.978723 (-3225 5475);
PAINT WHITE (-3225 5475);
DISPLAY INVISIBLE (-3225 5475);
FORCEPROP 1 LAST PART_NUMBER CS00002JB13
J 0
(-3225 5425);
DISPLAY 0.510638 (-3225 5425);
PAINT SKYBLUE (-3225 5425);
DISPLAY INVISIBLE (-3225 5425);
FORCEADD Q_RES..1
(-3175 5275);
FORCEPROP 1 LAST LOCATION R1331
J 0
(-3275 5275);
DISPLAY 0.489362 (-3275 5275);
PAINT SKYBLUE (-3275 5275);
FORCEPROP 0 LAST $SEC 1
J 0
(-3275 5325);
DISPLAY 0.680851 (-3275 5325);
PAINT MONO (-3275 5325);
DISPLAY INVISIBLE (-3275 5325);
FORCEPROP 0 LAST CDS_SEC 1
J 0
(-3275 5325);
DISPLAY 0.680851 (-3275 5325);
DISPLAY INVISIBLE (-3275 5325);
FORCEPROP 1 LASTPIN (-3275 5275) $PN 1
J 0
(-3263 5287);
DISPLAY 0.489362 (-3263 5287);
PAINT MONO (-3263 5287);
FORCEPROP 1 LASTPIN (-3075 5275) $PN 2
J 0
(-3113 5287);
DISPLAY 0.489362 (-3113 5287);
PAINT MONO (-3113 5287);
FORCEPROP 1 LAST MATERIAL EMPTY
J 0
(-3050 5275);
DISPLAY 0.489362 (-3050 5275);
PAINT RED (-3050 5275);
FORCEPROP 1 LAST VALUE 0
J 2
(-3075 5275);
DISPLAY 0.489362 (-3075 5275);
PAINT SKYBLUE (-3075 5275);
FORCEPROP 2 LAST CDS_LIB pure_quanta
J 0
(-3175 5275);
DISPLAY INVISIBLE (-3175 5275);
FORCEPROP 1 LAST WATTAGE 1/16W
J 2
(-3200 5125);
DISPLAY 0.510638 (-3200 5125);
PAINT SKYBLUE (-3200 5125);
DISPLAY INVISIBLE (-3200 5125);
FORCEPROP 1 LAST TOLERANCE 5%
J 0
(-3175 5175);
DISPLAY 0.510638 (-3175 5175);
PAINT SKYBLUE (-3175 5175);
DISPLAY INVISIBLE (-3175 5175);
FORCEPROP 1 LAST PACK_TYPE 0402LF
J 0
(-2925 5125);
DISPLAY 0.510638 (-2925 5125);
PAINT SKYBLUE (-2925 5125);
DISPLAY INVISIBLE (-2925 5125);
FORCEPROP 1 LAST PATH I132
J 0
(-3225 5425);
DISPLAY 0.978723 (-3225 5425);
PAINT WHITE (-3225 5425);
DISPLAY INVISIBLE (-3225 5425);
FORCEPROP 1 LAST PART_NUMBER CS00002JB13
J 0
(-3225 5375);
DISPLAY 0.510638 (-3225 5375);
PAINT SKYBLUE (-3225 5375);
DISPLAY INVISIBLE (-3225 5375);
FORCEADD Q_RES..1
(-3125 3875);
FORCEPROP 1 LAST LOCATION R1333
J 0
(-3225 3875);
DISPLAY 0.489362 (-3225 3875);
PAINT SKYBLUE (-3225 3875);
FORCEPROP 0 LAST $SEC 1
J 0
(-3225 3925);
DISPLAY 0.680851 (-3225 3925);
PAINT MONO (-3225 3925);
DISPLAY INVISIBLE (-3225 3925);
FORCEPROP 0 LAST CDS_SEC 1
J 0
(-3225 3925);
DISPLAY 0.680851 (-3225 3925);
DISPLAY INVISIBLE (-3225 3925);
FORCEPROP 1 LASTPIN (-3225 3875) $PN 1
J 0
(-3213 3887);
DISPLAY 0.489362 (-3213 3887);
PAINT MONO (-3213 3887);
FORCEPROP 1 LASTPIN (-3025 3875) $PN 2
J 0
(-3063 3887);
DISPLAY 0.489362 (-3063 3887);
PAINT MONO (-3063 3887);
FORCEPROP 1 LAST MATERIAL EMPTY
J 0
(-3000 3875);
DISPLAY 0.489362 (-3000 3875);
PAINT RED (-3000 3875);
FORCEPROP 1 LAST VALUE 0
J 2
(-3025 3875);
DISPLAY 0.489362 (-3025 3875);
PAINT SKYBLUE (-3025 3875);
FORCEPROP 2 LAST CDS_LIB pure_quanta
J 0
(-3125 3875);
DISPLAY INVISIBLE (-3125 3875);
FORCEPROP 1 LAST WATTAGE 1/16W
J 2
(-3150 3725);
DISPLAY 0.510638 (-3150 3725);
PAINT SKYBLUE (-3150 3725);
DISPLAY INVISIBLE (-3150 3725);
FORCEPROP 1 LAST TOLERANCE 5%
J 0
(-3125 3775);
DISPLAY 0.510638 (-3125 3775);
PAINT SKYBLUE (-3125 3775);
DISPLAY INVISIBLE (-3125 3775);
FORCEPROP 1 LAST PACK_TYPE 0402LF
J 0
(-2875 3725);
DISPLAY 0.510638 (-2875 3725);
PAINT SKYBLUE (-2875 3725);
DISPLAY INVISIBLE (-2875 3725);
FORCEPROP 1 LAST PATH I133
J 0
(-3175 4025);
DISPLAY 0.978723 (-3175 4025);
PAINT WHITE (-3175 4025);
DISPLAY INVISIBLE (-3175 4025);
FORCEPROP 1 LAST PART_NUMBER CS00002JB13
J 0
(-3175 3975);
DISPLAY 0.510638 (-3175 3975);
PAINT SKYBLUE (-3175 3975);
DISPLAY INVISIBLE (-3175 3975);
FORCEADD Q_RES..1
(-3125 3925);
FORCEPROP 1 LAST LOCATION R1332
J 0
(-3225 3925);
DISPLAY 0.489362 (-3225 3925);
PAINT SKYBLUE (-3225 3925);
FORCEPROP 0 LAST $SEC 1
J 0
(-3225 3975);
DISPLAY 0.680851 (-3225 3975);
PAINT MONO (-3225 3975);
DISPLAY INVISIBLE (-3225 3975);
FORCEPROP 0 LAST CDS_SEC 1
J 0
(-3225 3975);
DISPLAY 0.680851 (-3225 3975);
DISPLAY INVISIBLE (-3225 3975);
FORCEPROP 1 LASTPIN (-3225 3925) $PN 1
J 0
(-3213 3937);
DISPLAY 0.489362 (-3213 3937);
PAINT MONO (-3213 3937);
FORCEPROP 1 LASTPIN (-3025 3925) $PN 2
J 0
(-3063 3937);
DISPLAY 0.489362 (-3063 3937);
PAINT MONO (-3063 3937);
FORCEPROP 1 LAST MATERIAL EMPTY
J 0
(-3000 3925);
DISPLAY 0.489362 (-3000 3925);
PAINT RED (-3000 3925);
FORCEPROP 1 LAST VALUE 0
J 2
(-3025 3925);
DISPLAY 0.489362 (-3025 3925);
PAINT SKYBLUE (-3025 3925);
FORCEPROP 2 LAST CDS_LIB pure_quanta
J 0
(-3125 3925);
DISPLAY INVISIBLE (-3125 3925);
FORCEPROP 1 LAST WATTAGE 1/16W
J 2
(-3150 3775);
DISPLAY 0.510638 (-3150 3775);
PAINT SKYBLUE (-3150 3775);
DISPLAY INVISIBLE (-3150 3775);
FORCEPROP 1 LAST TOLERANCE 5%
J 0
(-3125 3825);
DISPLAY 0.510638 (-3125 3825);
PAINT SKYBLUE (-3125 3825);
DISPLAY INVISIBLE (-3125 3825);
FORCEPROP 1 LAST PACK_TYPE 0402LF
J 0
(-2875 3775);
DISPLAY 0.510638 (-2875 3775);
PAINT SKYBLUE (-2875 3775);
DISPLAY INVISIBLE (-2875 3775);
FORCEPROP 1 LAST PATH I134
J 0
(-3175 4075);
DISPLAY 0.978723 (-3175 4075);
PAINT WHITE (-3175 4075);
DISPLAY INVISIBLE (-3175 4075);
FORCEPROP 1 LAST PART_NUMBER CS00002JB13
J 0
(-3175 4025);
DISPLAY 0.510638 (-3175 4025);
PAINT SKYBLUE (-3175 4025);
DISPLAY INVISIBLE (-3175 4025);
FORCEADD Q_RES..1
(-6050 3925);
FORCEPROP 1 LAST LOCATION R986
J 0
(-6225 3925);
DISPLAY 0.489362 (-6225 3925);
PAINT SKYBLUE (-6225 3925);
FORCEPROP 0 LAST $SEC 1
J 0
(-5925 3950);
DISPLAY 0.680851 (-5925 3950);
PAINT MONO (-5925 3950);
DISPLAY INVISIBLE (-5925 3950);
FORCEPROP 0 LAST CDS_SEC 1
J 0
(-5925 3950);
DISPLAY 1.021277 (-5925 3950);
DISPLAY INVISIBLE (-5925 3950);
FORCEPROP 1 LASTPIN (-6150 3925) $PN 1
J 0
(-6138 3937);
DISPLAY 0.489362 (-6138 3937);
PAINT MONO (-6138 3937);
FORCEPROP 1 LASTPIN (-5950 3925) $PN 2
J 0
(-5988 3937);
DISPLAY 0.489362 (-5988 3937);
PAINT MONO (-5988 3937);
FORCEPROP 1 LAST MATERIAL EMPTY
J 0
(-5925 3925);
DISPLAY 0.489362 (-5925 3925);
PAINT RED (-5925 3925);
FORCEPROP 1 LAST VALUE 0
J 2
(-5950 3925);
DISPLAY 0.489362 (-5950 3925);
PAINT SKYBLUE (-5950 3925);
FORCEPROP 2 LAST CDS_LIB pure_quanta
J 0
(-6050 3925);
DISPLAY INVISIBLE (-6050 3925);
FORCEPROP 1 LAST WATTAGE 1/16W
J 2
(-6075 3775);
DISPLAY 0.510638 (-6075 3775);
PAINT SKYBLUE (-6075 3775);
DISPLAY INVISIBLE (-6075 3775);
FORCEPROP 1 LAST TOLERANCE 5%
J 0
(-6050 3825);
DISPLAY 0.510638 (-6050 3825);
PAINT SKYBLUE (-6050 3825);
DISPLAY INVISIBLE (-6050 3825);
FORCEPROP 1 LAST PACK_TYPE 0402LF
J 0
(-5800 3775);
DISPLAY 0.510638 (-5800 3775);
PAINT SKYBLUE (-5800 3775);
DISPLAY INVISIBLE (-5800 3775);
FORCEPROP 1 LAST PATH I135
J 0
(-6100 4075);
DISPLAY 0.978723 (-6100 4075);
PAINT WHITE (-6100 4075);
DISPLAY INVISIBLE (-6100 4075);
FORCEPROP 1 LAST PART_NUMBER CS00002JB13
J 0
(-6100 4025);
DISPLAY 0.510638 (-6100 4025);
PAINT SKYBLUE (-6100 4025);
DISPLAY INVISIBLE (-6100 4025);
FORCEADD Q_RES..1
(-6050 3875);
FORCEPROP 1 LAST LOCATION R987
J 0
(-6225 3875);
DISPLAY 0.489362 (-6225 3875);
PAINT SKYBLUE (-6225 3875);
FORCEPROP 0 LAST $SEC 1
J 0
(-5925 3900);
DISPLAY 0.680851 (-5925 3900);
PAINT MONO (-5925 3900);
DISPLAY INVISIBLE (-5925 3900);
FORCEPROP 0 LAST CDS_SEC 1
J 0
(-5925 3900);
DISPLAY 1.021277 (-5925 3900);
DISPLAY INVISIBLE (-5925 3900);
FORCEPROP 1 LASTPIN (-6150 3875) $PN 1
J 0
(-6138 3887);
DISPLAY 0.489362 (-6138 3887);
PAINT MONO (-6138 3887);
FORCEPROP 1 LASTPIN (-5950 3875) $PN 2
J 0
(-5988 3887);
DISPLAY 0.489362 (-5988 3887);
PAINT MONO (-5988 3887);
FORCEPROP 1 LAST MATERIAL EMPTY
J 0
(-5925 3875);
DISPLAY 0.489362 (-5925 3875);
PAINT RED (-5925 3875);
FORCEPROP 1 LAST VALUE 0
J 2
(-5950 3875);
DISPLAY 0.489362 (-5950 3875);
PAINT SKYBLUE (-5950 3875);
FORCEPROP 2 LAST CDS_LIB pure_quanta
J 0
(-6050 3875);
DISPLAY INVISIBLE (-6050 3875);
FORCEPROP 1 LAST WATTAGE 1/16W
J 2
(-6075 3725);
DISPLAY 0.510638 (-6075 3725);
PAINT SKYBLUE (-6075 3725);
DISPLAY INVISIBLE (-6075 3725);
FORCEPROP 1 LAST TOLERANCE 5%
J 0
(-6050 3775);
DISPLAY 0.510638 (-6050 3775);
PAINT SKYBLUE (-6050 3775);
DISPLAY INVISIBLE (-6050 3775);
FORCEPROP 1 LAST PACK_TYPE 0402LF
J 0
(-5800 3725);
DISPLAY 0.510638 (-5800 3725);
PAINT SKYBLUE (-5800 3725);
DISPLAY INVISIBLE (-5800 3725);
FORCEPROP 1 LAST PATH I136
J 0
(-6100 4025);
DISPLAY 0.978723 (-6100 4025);
PAINT WHITE (-6100 4025);
DISPLAY INVISIBLE (-6100 4025);
FORCEPROP 1 LAST PART_NUMBER CS00002JB13
J 0
(-6100 3975);
DISPLAY 0.510638 (-6100 3975);
PAINT SKYBLUE (-6100 3975);
DISPLAY INVISIBLE (-6100 3975);
FORCEADD Q_RES..1
(-6000 2350);
FORCEPROP 1 LAST LOCATION R989
J 0
(-6175 2350);
DISPLAY 0.489362 (-6175 2350);
PAINT SKYBLUE (-6175 2350);
FORCEPROP 0 LAST $SEC 1
J 0
(-5875 2375);
DISPLAY 0.680851 (-5875 2375);
PAINT MONO (-5875 2375);
DISPLAY INVISIBLE (-5875 2375);
FORCEPROP 0 LAST CDS_SEC 1
J 0
(-5875 2375);
DISPLAY 1.021277 (-5875 2375);
DISPLAY INVISIBLE (-5875 2375);
FORCEPROP 1 LASTPIN (-6100 2350) $PN 1
J 0
(-6088 2362);
DISPLAY 0.489362 (-6088 2362);
PAINT MONO (-6088 2362);
FORCEPROP 1 LASTPIN (-5900 2350) $PN 2
J 0
(-5938 2362);
DISPLAY 0.489362 (-5938 2362);
PAINT MONO (-5938 2362);
FORCEPROP 1 LAST VALUE 0
J 2
(-5900 2350);
DISPLAY 0.489362 (-5900 2350);
PAINT SKYBLUE (-5900 2350);
FORCEPROP 1 LAST MATERIAL EMPTY
J 0
(-5875 2350);
DISPLAY 0.489362 (-5875 2350);
PAINT RED (-5875 2350);
FORCEPROP 2 LAST CDS_LIB pure_quanta
J 0
(-6000 2350);
DISPLAY INVISIBLE (-6000 2350);
FORCEPROP 1 LAST WATTAGE 1/16W
J 2
(-6025 2200);
DISPLAY 0.510638 (-6025 2200);
PAINT SKYBLUE (-6025 2200);
DISPLAY INVISIBLE (-6025 2200);
FORCEPROP 1 LAST TOLERANCE 5%
J 0
(-6000 2250);
DISPLAY 0.510638 (-6000 2250);
PAINT SKYBLUE (-6000 2250);
DISPLAY INVISIBLE (-6000 2250);
FORCEPROP 1 LAST PACK_TYPE 0402LF
J 0
(-5750 2200);
DISPLAY 0.510638 (-5750 2200);
PAINT SKYBLUE (-5750 2200);
DISPLAY INVISIBLE (-5750 2200);
FORCEPROP 1 LAST PATH I137
J 0
(-6050 2500);
DISPLAY 0.978723 (-6050 2500);
PAINT WHITE (-6050 2500);
DISPLAY INVISIBLE (-6050 2500);
FORCEPROP 1 LAST PART_NUMBER CS00002JB13
J 0
(-6050 2450);
DISPLAY 0.510638 (-6050 2450);
PAINT SKYBLUE (-6050 2450);
DISPLAY INVISIBLE (-6050 2450);
FORCEADD Q_RES..1
(-6000 2400);
FORCEPROP 1 LAST LOCATION R988
J 0
(-6175 2400);
DISPLAY 0.489362 (-6175 2400);
PAINT SKYBLUE (-6175 2400);
FORCEPROP 0 LAST $SEC 1
J 0
(-5875 2425);
DISPLAY 0.680851 (-5875 2425);
PAINT MONO (-5875 2425);
DISPLAY INVISIBLE (-5875 2425);
FORCEPROP 0 LAST CDS_SEC 1
J 0
(-5875 2425);
DISPLAY 1.021277 (-5875 2425);
DISPLAY INVISIBLE (-5875 2425);
FORCEPROP 1 LASTPIN (-6100 2400) $PN 1
J 0
(-6088 2412);
DISPLAY 0.489362 (-6088 2412);
PAINT MONO (-6088 2412);
FORCEPROP 1 LASTPIN (-5900 2400) $PN 2
J 0
(-5938 2412);
DISPLAY 0.489362 (-5938 2412);
PAINT MONO (-5938 2412);
FORCEPROP 1 LAST VALUE 0
J 2
(-5900 2400);
DISPLAY 0.489362 (-5900 2400);
PAINT SKYBLUE (-5900 2400);
FORCEPROP 1 LAST MATERIAL EMPTY
J 0
(-5875 2400);
DISPLAY 0.489362 (-5875 2400);
PAINT RED (-5875 2400);
FORCEPROP 2 LAST CDS_LIB pure_quanta
J 0
(-6000 2400);
DISPLAY INVISIBLE (-6000 2400);
FORCEPROP 1 LAST WATTAGE 1/16W
J 2
(-6025 2250);
DISPLAY 0.510638 (-6025 2250);
PAINT SKYBLUE (-6025 2250);
DISPLAY INVISIBLE (-6025 2250);
FORCEPROP 1 LAST TOLERANCE 5%
J 0
(-6000 2300);
DISPLAY 0.510638 (-6000 2300);
PAINT SKYBLUE (-6000 2300);
DISPLAY INVISIBLE (-6000 2300);
FORCEPROP 1 LAST PACK_TYPE 0402LF
J 0
(-5750 2250);
DISPLAY 0.510638 (-5750 2250);
PAINT SKYBLUE (-5750 2250);
DISPLAY INVISIBLE (-5750 2250);
FORCEPROP 1 LAST PATH I138
J 0
(-6050 2550);
DISPLAY 0.978723 (-6050 2550);
PAINT WHITE (-6050 2550);
DISPLAY INVISIBLE (-6050 2550);
FORCEPROP 1 LAST PART_NUMBER CS00002JB13
J 0
(-6050 2500);
DISPLAY 0.510638 (-6050 2500);
PAINT SKYBLUE (-6050 2500);
DISPLAY INVISIBLE (-6050 2500);
FORCEADD Q_RES..1
(-3075 2400);
FORCEPROP 1 LAST LOCATION R1334
J 0
(-3175 2400);
DISPLAY 0.489362 (-3175 2400);
PAINT SKYBLUE (-3175 2400);
FORCEPROP 0 LAST $SEC 1
J 0
(-3175 2450);
DISPLAY 0.680851 (-3175 2450);
PAINT MONO (-3175 2450);
DISPLAY INVISIBLE (-3175 2450);
FORCEPROP 0 LAST CDS_SEC 1
J 0
(-3175 2450);
DISPLAY 0.680851 (-3175 2450);
DISPLAY INVISIBLE (-3175 2450);
FORCEPROP 1 LASTPIN (-3175 2400) $PN 1
J 0
(-3163 2412);
DISPLAY 0.489362 (-3163 2412);
PAINT MONO (-3163 2412);
FORCEPROP 1 LASTPIN (-2975 2400) $PN 2
J 0
(-3013 2412);
DISPLAY 0.489362 (-3013 2412);
PAINT MONO (-3013 2412);
FORCEPROP 1 LAST MATERIAL EMPTY
J 0
(-2950 2400);
DISPLAY 0.489362 (-2950 2400);
PAINT RED (-2950 2400);
FORCEPROP 1 LAST VALUE 0
J 2
(-2975 2400);
DISPLAY 0.489362 (-2975 2400);
PAINT SKYBLUE (-2975 2400);
FORCEPROP 2 LAST CDS_LIB pure_quanta
J 0
(-3075 2400);
DISPLAY INVISIBLE (-3075 2400);
FORCEPROP 1 LAST WATTAGE 1/16W
J 2
(-3100 2250);
DISPLAY 0.510638 (-3100 2250);
PAINT SKYBLUE (-3100 2250);
DISPLAY INVISIBLE (-3100 2250);
FORCEPROP 1 LAST TOLERANCE 5%
J 0
(-3075 2300);
DISPLAY 0.510638 (-3075 2300);
PAINT SKYBLUE (-3075 2300);
DISPLAY INVISIBLE (-3075 2300);
FORCEPROP 1 LAST PACK_TYPE 0402LF
J 0
(-2825 2250);
DISPLAY 0.510638 (-2825 2250);
PAINT SKYBLUE (-2825 2250);
DISPLAY INVISIBLE (-2825 2250);
FORCEPROP 1 LAST PATH I139
J 0
(-3125 2550);
DISPLAY 0.978723 (-3125 2550);
PAINT WHITE (-3125 2550);
DISPLAY INVISIBLE (-3125 2550);
FORCEPROP 1 LAST PART_NUMBER CS00002JB13
J 0
(-3125 2500);
DISPLAY 0.510638 (-3125 2500);
PAINT SKYBLUE (-3125 2500);
DISPLAY INVISIBLE (-3125 2500);
FORCEADD OFFPAGE..3
R 2
(-6025 5625);
FORCEPROP 2 LAST $XR0 150 
J 0
(-6335 5625);
DISPLAY 0.638298 (-6335 5625);
PAINT MONO (-6335 5625);
FORCEPROP 2 LAST CDS_LIB standard
J 2
(-6025 5625);
DISPLAY INVISIBLE (-6025 5625);
FORCEPROP 1 LAST OFFPAGE TRUE
J 2
(-6350 5500);
DISPLAY 0.872340 (-6350 5500);
PAINT GREEN (-6350 5500);
DISPLAY INVISIBLE (-6350 5500);
FORCEPROP 1 LAST COMMENT_BODY TRUE
J 2
(-5975 5525);
DISPLAY 0.872340 (-5975 5525);
PAINT GREEN (-5975 5525);
DISPLAY INVISIBLE (-5975 5525);
FORCEPROP 2 LAST PATH I14
J 0
(-5975 5700);
DISPLAY 1.021277 (-5975 5700);
DISPLAY INVISIBLE (-5975 5700);
FORCEADD Q_RES..1
(-3075 2350);
FORCEPROP 1 LAST LOCATION R1335
J 0
(-3175 2350);
DISPLAY 0.489362 (-3175 2350);
PAINT SKYBLUE (-3175 2350);
FORCEPROP 0 LAST $SEC 1
J 0
(-3175 2400);
DISPLAY 0.680851 (-3175 2400);
PAINT MONO (-3175 2400);
DISPLAY INVISIBLE (-3175 2400);
FORCEPROP 0 LAST CDS_SEC 1
J 0
(-3175 2400);
DISPLAY 0.680851 (-3175 2400);
DISPLAY INVISIBLE (-3175 2400);
FORCEPROP 1 LASTPIN (-3175 2350) $PN 1
J 0
(-3163 2362);
DISPLAY 0.489362 (-3163 2362);
PAINT MONO (-3163 2362);
FORCEPROP 1 LASTPIN (-2975 2350) $PN 2
J 0
(-3013 2362);
DISPLAY 0.489362 (-3013 2362);
PAINT MONO (-3013 2362);
FORCEPROP 1 LAST MATERIAL EMPTY
J 0
(-2950 2350);
DISPLAY 0.489362 (-2950 2350);
PAINT RED (-2950 2350);
FORCEPROP 1 LAST VALUE 0
J 2
(-2975 2350);
DISPLAY 0.489362 (-2975 2350);
PAINT SKYBLUE (-2975 2350);
FORCEPROP 2 LAST CDS_LIB pure_quanta
J 0
(-3075 2350);
DISPLAY INVISIBLE (-3075 2350);
FORCEPROP 1 LAST WATTAGE 1/16W
J 2
(-3100 2200);
DISPLAY 0.510638 (-3100 2200);
PAINT SKYBLUE (-3100 2200);
DISPLAY INVISIBLE (-3100 2200);
FORCEPROP 1 LAST TOLERANCE 5%
J 0
(-3075 2250);
DISPLAY 0.510638 (-3075 2250);
PAINT SKYBLUE (-3075 2250);
DISPLAY INVISIBLE (-3075 2250);
FORCEPROP 1 LAST PACK_TYPE 0402LF
J 0
(-2825 2200);
DISPLAY 0.510638 (-2825 2200);
PAINT SKYBLUE (-2825 2200);
DISPLAY INVISIBLE (-2825 2200);
FORCEPROP 1 LAST PATH I140
J 0
(-3125 2500);
DISPLAY 0.978723 (-3125 2500);
PAINT WHITE (-3125 2500);
DISPLAY INVISIBLE (-3125 2500);
FORCEPROP 1 LAST PART_NUMBER CS00002JB13
J 0
(-3125 2450);
DISPLAY 0.510638 (-3125 2450);
PAINT SKYBLUE (-3125 2450);
DISPLAY INVISIBLE (-3125 2450);
FORCEADD Q_RES..1
(-5950 900);
FORCEPROP 1 LAST LOCATION R991
J 0
(-6125 900);
DISPLAY 0.489362 (-6125 900);
PAINT SKYBLUE (-6125 900);
FORCEPROP 0 LAST $SEC 1
J 0
(-5825 925);
DISPLAY 0.680851 (-5825 925);
PAINT MONO (-5825 925);
DISPLAY INVISIBLE (-5825 925);
FORCEPROP 0 LAST CDS_SEC 1
J 0
(-5825 925);
DISPLAY 1.021277 (-5825 925);
DISPLAY INVISIBLE (-5825 925);
FORCEPROP 1 LASTPIN (-6050 900) $PN 1
J 0
(-6038 912);
DISPLAY 0.489362 (-6038 912);
PAINT MONO (-6038 912);
FORCEPROP 1 LASTPIN (-5850 900) $PN 2
J 0
(-5888 912);
DISPLAY 0.489362 (-5888 912);
PAINT MONO (-5888 912);
FORCEPROP 1 LAST MATERIAL EMPTY
J 0
(-5825 900);
DISPLAY 0.489362 (-5825 900);
PAINT RED (-5825 900);
FORCEPROP 1 LAST VALUE 0
J 2
(-5850 900);
DISPLAY 0.489362 (-5850 900);
PAINT SKYBLUE (-5850 900);
FORCEPROP 2 LAST CDS_LIB pure_quanta
J 0
(-5950 900);
DISPLAY INVISIBLE (-5950 900);
FORCEPROP 1 LAST WATTAGE 1/16W
J 2
(-5975 750);
DISPLAY 0.510638 (-5975 750);
PAINT SKYBLUE (-5975 750);
DISPLAY INVISIBLE (-5975 750);
FORCEPROP 1 LAST TOLERANCE 5%
J 0
(-5950 800);
DISPLAY 0.510638 (-5950 800);
PAINT SKYBLUE (-5950 800);
DISPLAY INVISIBLE (-5950 800);
FORCEPROP 1 LAST PACK_TYPE 0402LF
J 0
(-5700 750);
DISPLAY 0.510638 (-5700 750);
PAINT SKYBLUE (-5700 750);
DISPLAY INVISIBLE (-5700 750);
FORCEPROP 1 LAST PATH I141
J 0
(-6000 1050);
DISPLAY 0.978723 (-6000 1050);
PAINT WHITE (-6000 1050);
DISPLAY INVISIBLE (-6000 1050);
FORCEPROP 1 LAST PART_NUMBER CS00002JB13
J 0
(-6000 1000);
DISPLAY 0.510638 (-6000 1000);
PAINT SKYBLUE (-6000 1000);
DISPLAY INVISIBLE (-6000 1000);
FORCEADD Q_RES..1
(-5950 950);
FORCEPROP 1 LAST LOCATION R990
J 0
(-6125 950);
DISPLAY 0.489362 (-6125 950);
PAINT SKYBLUE (-6125 950);
FORCEPROP 0 LAST $SEC 1
J 0
(-5825 975);
DISPLAY 0.680851 (-5825 975);
PAINT MONO (-5825 975);
DISPLAY INVISIBLE (-5825 975);
FORCEPROP 0 LAST CDS_SEC 1
J 0
(-5825 975);
DISPLAY 1.021277 (-5825 975);
DISPLAY INVISIBLE (-5825 975);
FORCEPROP 1 LASTPIN (-6050 950) $PN 1
J 0
(-6038 962);
DISPLAY 0.489362 (-6038 962);
PAINT MONO (-6038 962);
FORCEPROP 1 LASTPIN (-5850 950) $PN 2
J 0
(-5888 962);
DISPLAY 0.489362 (-5888 962);
PAINT MONO (-5888 962);
FORCEPROP 1 LAST MATERIAL EMPTY
J 0
(-5825 950);
DISPLAY 0.489362 (-5825 950);
PAINT RED (-5825 950);
FORCEPROP 1 LAST VALUE 0
J 2
(-5850 950);
DISPLAY 0.489362 (-5850 950);
PAINT SKYBLUE (-5850 950);
FORCEPROP 2 LAST CDS_LIB pure_quanta
J 0
(-5950 950);
DISPLAY INVISIBLE (-5950 950);
FORCEPROP 1 LAST WATTAGE 1/16W
J 2
(-5975 800);
DISPLAY 0.510638 (-5975 800);
PAINT SKYBLUE (-5975 800);
DISPLAY INVISIBLE (-5975 800);
FORCEPROP 1 LAST TOLERANCE 5%
J 0
(-5950 850);
DISPLAY 0.510638 (-5950 850);
PAINT SKYBLUE (-5950 850);
DISPLAY INVISIBLE (-5950 850);
FORCEPROP 1 LAST PACK_TYPE 0402LF
J 0
(-5700 800);
DISPLAY 0.510638 (-5700 800);
PAINT SKYBLUE (-5700 800);
DISPLAY INVISIBLE (-5700 800);
FORCEPROP 1 LAST PATH I142
J 0
(-6000 1100);
DISPLAY 0.978723 (-6000 1100);
PAINT WHITE (-6000 1100);
DISPLAY INVISIBLE (-6000 1100);
FORCEPROP 1 LAST PART_NUMBER CS00002JB13
J 0
(-6000 1050);
DISPLAY 0.510638 (-6000 1050);
PAINT SKYBLUE (-6000 1050);
DISPLAY INVISIBLE (-6000 1050);
FORCEADD Q_RES..1
(-3025 950);
FORCEPROP 1 LAST LOCATION R1336
J 0
(-3125 950);
DISPLAY 0.489362 (-3125 950);
PAINT SKYBLUE (-3125 950);
FORCEPROP 0 LAST $SEC 1
J 0
(-3125 1000);
DISPLAY 0.680851 (-3125 1000);
PAINT MONO (-3125 1000);
DISPLAY INVISIBLE (-3125 1000);
FORCEPROP 0 LAST CDS_SEC 1
J 0
(-3125 1000);
DISPLAY 0.680851 (-3125 1000);
DISPLAY INVISIBLE (-3125 1000);
FORCEPROP 1 LASTPIN (-3125 950) $PN 1
J 0
(-3113 962);
DISPLAY 0.489362 (-3113 962);
PAINT MONO (-3113 962);
FORCEPROP 1 LASTPIN (-2925 950) $PN 2
J 0
(-2963 962);
DISPLAY 0.489362 (-2963 962);
PAINT MONO (-2963 962);
FORCEPROP 1 LAST MATERIAL EMPTY
J 0
(-2900 950);
DISPLAY 0.489362 (-2900 950);
PAINT RED (-2900 950);
FORCEPROP 1 LAST VALUE 0
J 2
(-2925 950);
DISPLAY 0.489362 (-2925 950);
PAINT SKYBLUE (-2925 950);
FORCEPROP 2 LAST CDS_LIB pure_quanta
J 0
(-3025 950);
DISPLAY INVISIBLE (-3025 950);
FORCEPROP 1 LAST WATTAGE 1/16W
J 2
(-3050 800);
DISPLAY 0.510638 (-3050 800);
PAINT SKYBLUE (-3050 800);
DISPLAY INVISIBLE (-3050 800);
FORCEPROP 1 LAST TOLERANCE 5%
J 0
(-3025 850);
DISPLAY 0.510638 (-3025 850);
PAINT SKYBLUE (-3025 850);
DISPLAY INVISIBLE (-3025 850);
FORCEPROP 1 LAST PACK_TYPE 0402LF
J 0
(-2775 800);
DISPLAY 0.510638 (-2775 800);
PAINT SKYBLUE (-2775 800);
DISPLAY INVISIBLE (-2775 800);
FORCEPROP 1 LAST PATH I143
J 0
(-3075 1100);
DISPLAY 0.978723 (-3075 1100);
PAINT WHITE (-3075 1100);
DISPLAY INVISIBLE (-3075 1100);
FORCEPROP 1 LAST PART_NUMBER CS00002JB13
J 0
(-3075 1050);
DISPLAY 0.510638 (-3075 1050);
PAINT SKYBLUE (-3075 1050);
DISPLAY INVISIBLE (-3075 1050);
FORCEADD Q_RES..1
(-3025 900);
FORCEPROP 1 LAST LOCATION R1337
J 0
(-3125 900);
DISPLAY 0.489362 (-3125 900);
PAINT SKYBLUE (-3125 900);
FORCEPROP 0 LAST $SEC 1
J 0
(-3125 950);
DISPLAY 0.680851 (-3125 950);
PAINT MONO (-3125 950);
DISPLAY INVISIBLE (-3125 950);
FORCEPROP 0 LAST CDS_SEC 1
J 0
(-3125 950);
DISPLAY 0.680851 (-3125 950);
DISPLAY INVISIBLE (-3125 950);
FORCEPROP 1 LASTPIN (-3125 900) $PN 1
J 0
(-3113 912);
DISPLAY 0.489362 (-3113 912);
PAINT MONO (-3113 912);
FORCEPROP 1 LASTPIN (-2925 900) $PN 2
J 0
(-2963 912);
DISPLAY 0.489362 (-2963 912);
PAINT MONO (-2963 912);
FORCEPROP 1 LAST MATERIAL EMPTY
J 0
(-2900 900);
DISPLAY 0.489362 (-2900 900);
PAINT RED (-2900 900);
FORCEPROP 1 LAST VALUE 0
J 2
(-2925 900);
DISPLAY 0.489362 (-2925 900);
PAINT SKYBLUE (-2925 900);
FORCEPROP 2 LAST CDS_LIB pure_quanta
J 0
(-3025 900);
DISPLAY INVISIBLE (-3025 900);
FORCEPROP 1 LAST WATTAGE 1/16W
J 2
(-3050 750);
DISPLAY 0.510638 (-3050 750);
PAINT SKYBLUE (-3050 750);
DISPLAY INVISIBLE (-3050 750);
FORCEPROP 1 LAST TOLERANCE 5%
J 0
(-3025 800);
DISPLAY 0.510638 (-3025 800);
PAINT SKYBLUE (-3025 800);
DISPLAY INVISIBLE (-3025 800);
FORCEPROP 1 LAST PACK_TYPE 0402LF
J 0
(-2775 750);
DISPLAY 0.510638 (-2775 750);
PAINT SKYBLUE (-2775 750);
DISPLAY INVISIBLE (-2775 750);
FORCEPROP 1 LAST PATH I144
J 0
(-3075 1050);
DISPLAY 0.978723 (-3075 1050);
PAINT WHITE (-3075 1050);
DISPLAY INVISIBLE (-3075 1050);
FORCEPROP 1 LAST PART_NUMBER CS00002JB13
J 0
(-3075 1000);
DISPLAY 0.510638 (-3075 1000);
PAINT SKYBLUE (-3075 1000);
DISPLAY INVISIBLE (-3075 1000);
FORCEADD Q_RES..2
(-3450 6100);
FORCEPROP 1 LAST LOCATION R5006
J 0
(-3405 6225);
DISPLAY 0.489362 (-3405 6225);
PAINT SKYBLUE (-3405 6225);
FORCEPROP 0 LAST $SEC 1
J 0
(-3400 6250);
DISPLAY 0.680851 (-3400 6250);
PAINT MONO (-3400 6250);
DISPLAY INVISIBLE (-3400 6250);
FORCEPROP 0 LAST CDS_SEC 1
J 0
(-3400 6250);
DISPLAY 0.680851 (-3400 6250);
DISPLAY INVISIBLE (-3400 6250);
FORCEPROP 1 LASTPIN (-3450 6200) $PN 1
J 0
(-3445 6162);
DISPLAY 0.787234 (-3445 6162);
PAINT MONO (-3445 6162);
FORCEPROP 1 LASTPIN (-3450 6000) $PN 2
J 0
(-3445 6010);
DISPLAY 0.787234 (-3445 6010);
PAINT MONO (-3445 6010);
FORCEPROP 1 LAST WATTAGE 1/16W
J 0
(-3410 6075);
DISPLAY 0.489362 (-3410 6075);
PAINT SKYBLUE (-3410 6075);
FORCEPROP 1 LAST PACK_TYPE 0402LF
J 0
(-3400 5975);
DISPLAY 0.489362 (-3400 5975);
PAINT SKYBLUE (-3400 5975);
FORCEPROP 1 LAST VALUE 1K
J 0
(-3405 6175);
DISPLAY 0.489362 (-3405 6175);
PAINT SKYBLUE (-3405 6175);
FORCEPROP 1 LAST TOLERANCE 1%
J 0
(-3405 6125);
DISPLAY 0.489362 (-3405 6125);
PAINT SKYBLUE (-3405 6125);
FORCEPROP 1 LAST MATERIAL EMPTY
J 0
(-3410 6025);
DISPLAY 0.489362 (-3410 6025);
PAINT SKYBLUE (-3410 6025);
FORCEPROP 2 LAST CDS_LIB pure_quanta
J 0
(-3450 6100);
DISPLAY INVISIBLE (-3450 6100);
FORCEPROP 1 LAST PATH I145
J 0
(-3400 6275);
DISPLAY 0.978723 (-3400 6275);
PAINT WHITE (-3400 6275);
DISPLAY INVISIBLE (-3400 6275);
FORCEPROP 1 LAST PART_NUMBER CS21002FB06
J 0
(-3410 5975);
DISPLAY 0.489362 (-3410 5975);
PAINT SKYBLUE (-3410 5975);
DISPLAY INVISIBLE (-3410 5975);
FORCEADD VCC_CORE..1
(-3450 6375);
FORCEPROP 3 LASTPIN (-3450 6325) SIG_NAME PVDD11_S3_P0\g
J 0
(-3440 6335);
DISPLAY 0.659574 (-3440 6335);
PAINT MONO (-3440 6335);
DISPLAY INVISIBLE (-3440 6335);
FORCEPROP 1 LAST HDL_POWER PVDD11_S3_P0
J 1
(-3450 6425);
DISPLAY 0.489362 (-3450 6425);
PAINT GREEN (-3450 6425);
FORCEPROP 2 LAST CDS_LIB pure_quanta_power
J 0
(-3450 6375);
DISPLAY INVISIBLE (-3450 6375);
FORCEPROP 1 LAST PATH I146
J 0
(-3400 6400);
DISPLAY 0.872340 (-3400 6400);
PAINT AQUA (-3400 6400);
DISPLAY INVISIBLE (-3400 6400);
FORCEADD Q_RES..2
(-3650 6100);
FORCEPROP 1 LAST LOCATION R5007
J 0
(-3605 6225);
DISPLAY 0.489362 (-3605 6225);
PAINT SKYBLUE (-3605 6225);
FORCEPROP 0 LAST $SEC 1
J 0
(-3600 6250);
DISPLAY 0.680851 (-3600 6250);
PAINT MONO (-3600 6250);
DISPLAY INVISIBLE (-3600 6250);
FORCEPROP 0 LAST CDS_SEC 1
J 0
(-3600 6250);
DISPLAY 0.680851 (-3600 6250);
DISPLAY INVISIBLE (-3600 6250);
FORCEPROP 1 LASTPIN (-3650 6200) $PN 1
J 0
(-3645 6162);
DISPLAY 0.787234 (-3645 6162);
PAINT MONO (-3645 6162);
FORCEPROP 1 LASTPIN (-3650 6000) $PN 2
J 0
(-3645 6010);
DISPLAY 0.787234 (-3645 6010);
PAINT MONO (-3645 6010);
FORCEPROP 1 LAST WATTAGE 1/16W
J 0
(-3610 6075);
DISPLAY 0.489362 (-3610 6075);
PAINT SKYBLUE (-3610 6075);
FORCEPROP 1 LAST PACK_TYPE 0402LF
J 0
(-3600 5975);
DISPLAY 0.489362 (-3600 5975);
PAINT SKYBLUE (-3600 5975);
FORCEPROP 1 LAST TOLERANCE 1%
J 0
(-3605 6125);
DISPLAY 0.489362 (-3605 6125);
PAINT SKYBLUE (-3605 6125);
FORCEPROP 1 LAST MATERIAL EMPTY
J 0
(-3610 6025);
DISPLAY 0.489362 (-3610 6025);
PAINT SKYBLUE (-3610 6025);
FORCEPROP 1 LAST VALUE 1K
J 0
(-3605 6175);
DISPLAY 0.489362 (-3605 6175);
PAINT SKYBLUE (-3605 6175);
FORCEPROP 2 LAST CDS_LIB pure_quanta
J 0
(-3650 6100);
DISPLAY INVISIBLE (-3650 6100);
FORCEPROP 1 LAST PATH I147
J 0
(-3600 6275);
DISPLAY 0.978723 (-3600 6275);
PAINT WHITE (-3600 6275);
DISPLAY INVISIBLE (-3600 6275);
FORCEPROP 1 LAST PART_NUMBER CS21002FB06
J 0
(-3610 5975);
DISPLAY 0.489362 (-3610 5975);
PAINT SKYBLUE (-3610 5975);
DISPLAY INVISIBLE (-3610 5975);
FORCEADD Q_RES..2
(-3450 4700);
FORCEPROP 1 LAST LOCATION R5008
J 0
(-3405 4825);
DISPLAY 0.489362 (-3405 4825);
PAINT SKYBLUE (-3405 4825);
FORCEPROP 0 LAST $SEC 1
J 0
(-3400 4850);
DISPLAY 0.680851 (-3400 4850);
PAINT MONO (-3400 4850);
DISPLAY INVISIBLE (-3400 4850);
FORCEPROP 0 LAST CDS_SEC 1
J 0
(-3400 4850);
DISPLAY 0.680851 (-3400 4850);
DISPLAY INVISIBLE (-3400 4850);
FORCEPROP 1 LASTPIN (-3450 4800) $PN 1
J 0
(-3445 4762);
DISPLAY 0.787234 (-3445 4762);
PAINT MONO (-3445 4762);
FORCEPROP 1 LASTPIN (-3450 4600) $PN 2
J 0
(-3445 4610);
DISPLAY 0.787234 (-3445 4610);
PAINT MONO (-3445 4610);
FORCEPROP 1 LAST TOLERANCE 1%
J 0
(-3405 4725);
DISPLAY 0.489362 (-3405 4725);
PAINT SKYBLUE (-3405 4725);
FORCEPROP 1 LAST VALUE 1K
J 0
(-3405 4775);
DISPLAY 0.489362 (-3405 4775);
PAINT SKYBLUE (-3405 4775);
FORCEPROP 1 LAST PACK_TYPE 0402LF
J 0
(-3400 4575);
DISPLAY 0.489362 (-3400 4575);
PAINT SKYBLUE (-3400 4575);
FORCEPROP 1 LAST MATERIAL EMPTY
J 0
(-3410 4625);
DISPLAY 0.489362 (-3410 4625);
PAINT SKYBLUE (-3410 4625);
FORCEPROP 1 LAST WATTAGE 1/16W
J 0
(-3410 4675);
DISPLAY 0.489362 (-3410 4675);
PAINT SKYBLUE (-3410 4675);
FORCEPROP 2 LAST CDS_LIB pure_quanta
J 0
(-3450 4700);
DISPLAY INVISIBLE (-3450 4700);
FORCEPROP 1 LAST PATH I148
J 0
(-3400 4875);
DISPLAY 0.978723 (-3400 4875);
PAINT WHITE (-3400 4875);
DISPLAY INVISIBLE (-3400 4875);
FORCEPROP 1 LAST PART_NUMBER CS21002FB06
J 0
(-3410 4575);
DISPLAY 0.489362 (-3410 4575);
PAINT SKYBLUE (-3410 4575);
DISPLAY INVISIBLE (-3410 4575);
FORCEADD VCC_CORE..1
(-3450 4975);
FORCEPROP 3 LASTPIN (-3450 4925) SIG_NAME PVDD11_S3_P0\g
J 0
(-3440 4935);
DISPLAY 0.659574 (-3440 4935);
PAINT MONO (-3440 4935);
DISPLAY INVISIBLE (-3440 4935);
FORCEPROP 1 LAST HDL_POWER PVDD11_S3_P0
J 1
(-3450 5025);
DISPLAY 0.489362 (-3450 5025);
PAINT GREEN (-3450 5025);
FORCEPROP 2 LAST CDS_LIB pure_quanta_power
J 0
(-3450 4975);
DISPLAY INVISIBLE (-3450 4975);
FORCEPROP 1 LAST PATH I149
J 0
(-3400 5000);
DISPLAY 0.872340 (-3400 5000);
PAINT AQUA (-3400 5000);
DISPLAY INVISIBLE (-3400 5000);
FORCEADD OFFPAGE..1
(-6025 5675);
FORCEPROP 2 LAST $XR0 150 
J 0
(-6307 5675);
DISPLAY 0.638298 (-6307 5675);
PAINT MONO (-6307 5675);
FORCEPROP 2 LAST CDS_LIB standard
J 0
(-6025 5675);
DISPLAY INVISIBLE (-6025 5675);
FORCEPROP 1 LAST OFFPAGE TRUE
J 0
(-5700 5550);
DISPLAY 0.872340 (-5700 5550);
PAINT GREEN (-5700 5550);
DISPLAY INVISIBLE (-5700 5550);
FORCEPROP 1 LAST COMMENT_BODY TRUE
J 0
(-5900 5575);
DISPLAY 0.872340 (-5900 5575);
PAINT GREEN (-5900 5575);
DISPLAY INVISIBLE (-5900 5575);
FORCEPROP 2 LAST PATH I15
J 0
(-5975 5750);
DISPLAY 1.021277 (-5975 5750);
DISPLAY INVISIBLE (-5975 5750);
FORCEADD Q_RES..2
(-3650 4700);
FORCEPROP 1 LAST LOCATION R5009
J 0
(-3605 4825);
DISPLAY 0.489362 (-3605 4825);
PAINT SKYBLUE (-3605 4825);
FORCEPROP 0 LAST $SEC 1
J 0
(-3600 4850);
DISPLAY 0.680851 (-3600 4850);
PAINT MONO (-3600 4850);
DISPLAY INVISIBLE (-3600 4850);
FORCEPROP 0 LAST CDS_SEC 1
J 0
(-3600 4850);
DISPLAY 0.680851 (-3600 4850);
DISPLAY INVISIBLE (-3600 4850);
FORCEPROP 1 LASTPIN (-3650 4800) $PN 1
J 0
(-3645 4762);
DISPLAY 0.787234 (-3645 4762);
PAINT MONO (-3645 4762);
FORCEPROP 1 LASTPIN (-3650 4600) $PN 2
J 0
(-3645 4610);
DISPLAY 0.787234 (-3645 4610);
PAINT MONO (-3645 4610);
FORCEPROP 1 LAST TOLERANCE 1%
J 0
(-3605 4725);
DISPLAY 0.489362 (-3605 4725);
PAINT SKYBLUE (-3605 4725);
FORCEPROP 1 LAST WATTAGE 1/16W
J 0
(-3610 4675);
DISPLAY 0.489362 (-3610 4675);
PAINT SKYBLUE (-3610 4675);
FORCEPROP 1 LAST PACK_TYPE 0402LF
J 0
(-3600 4575);
DISPLAY 0.489362 (-3600 4575);
PAINT SKYBLUE (-3600 4575);
FORCEPROP 1 LAST MATERIAL EMPTY
J 0
(-3610 4625);
DISPLAY 0.489362 (-3610 4625);
PAINT SKYBLUE (-3610 4625);
FORCEPROP 1 LAST VALUE 1K
J 0
(-3605 4775);
DISPLAY 0.489362 (-3605 4775);
PAINT SKYBLUE (-3605 4775);
FORCEPROP 2 LAST CDS_LIB pure_quanta
J 0
(-3650 4700);
DISPLAY INVISIBLE (-3650 4700);
FORCEPROP 1 LAST PATH I150
J 0
(-3600 4875);
DISPLAY 0.978723 (-3600 4875);
PAINT WHITE (-3600 4875);
DISPLAY INVISIBLE (-3600 4875);
FORCEPROP 1 LAST PART_NUMBER CS21002FB06
J 0
(-3610 4575);
DISPLAY 0.489362 (-3610 4575);
PAINT SKYBLUE (-3610 4575);
DISPLAY INVISIBLE (-3610 4575);
FORCEADD Q_RES..2
(-3450 3175);
FORCEPROP 1 LAST LOCATION R5010
J 0
(-3405 3300);
DISPLAY 0.489362 (-3405 3300);
PAINT SKYBLUE (-3405 3300);
FORCEPROP 0 LAST $SEC 1
J 0
(-3400 3325);
DISPLAY 0.680851 (-3400 3325);
PAINT MONO (-3400 3325);
DISPLAY INVISIBLE (-3400 3325);
FORCEPROP 0 LAST CDS_SEC 1
J 0
(-3400 3325);
DISPLAY 0.680851 (-3400 3325);
DISPLAY INVISIBLE (-3400 3325);
FORCEPROP 1 LASTPIN (-3450 3275) $PN 1
J 0
(-3445 3237);
DISPLAY 0.787234 (-3445 3237);
PAINT MONO (-3445 3237);
FORCEPROP 1 LASTPIN (-3450 3075) $PN 2
J 0
(-3445 3085);
DISPLAY 0.787234 (-3445 3085);
PAINT MONO (-3445 3085);
FORCEPROP 1 LAST WATTAGE 1/16W
J 0
(-3410 3150);
DISPLAY 0.489362 (-3410 3150);
PAINT SKYBLUE (-3410 3150);
FORCEPROP 1 LAST TOLERANCE 1%
J 0
(-3405 3200);
DISPLAY 0.489362 (-3405 3200);
PAINT SKYBLUE (-3405 3200);
FORCEPROP 1 LAST PACK_TYPE 0402LF
J 0
(-3400 3050);
DISPLAY 0.489362 (-3400 3050);
PAINT SKYBLUE (-3400 3050);
FORCEPROP 1 LAST VALUE 1K
J 0
(-3405 3250);
DISPLAY 0.489362 (-3405 3250);
PAINT SKYBLUE (-3405 3250);
FORCEPROP 1 LAST MATERIAL EMPTY
J 0
(-3410 3100);
DISPLAY 0.489362 (-3410 3100);
PAINT SKYBLUE (-3410 3100);
FORCEPROP 2 LAST CDS_LIB pure_quanta
J 0
(-3450 3175);
DISPLAY INVISIBLE (-3450 3175);
FORCEPROP 1 LAST PATH I151
J 0
(-3400 3350);
DISPLAY 0.978723 (-3400 3350);
PAINT WHITE (-3400 3350);
DISPLAY INVISIBLE (-3400 3350);
FORCEPROP 1 LAST PART_NUMBER CS21002FB06
J 0
(-3410 3050);
DISPLAY 0.489362 (-3410 3050);
PAINT SKYBLUE (-3410 3050);
DISPLAY INVISIBLE (-3410 3050);
FORCEADD Q_RES..2
(-3650 3175);
FORCEPROP 1 LAST LOCATION R5011
J 0
(-3605 3300);
DISPLAY 0.489362 (-3605 3300);
PAINT SKYBLUE (-3605 3300);
FORCEPROP 0 LAST $SEC 1
J 0
(-3600 3325);
DISPLAY 0.680851 (-3600 3325);
PAINT MONO (-3600 3325);
DISPLAY INVISIBLE (-3600 3325);
FORCEPROP 0 LAST CDS_SEC 1
J 0
(-3600 3325);
DISPLAY 0.680851 (-3600 3325);
DISPLAY INVISIBLE (-3600 3325);
FORCEPROP 1 LASTPIN (-3650 3275) $PN 1
J 0
(-3645 3237);
DISPLAY 0.787234 (-3645 3237);
PAINT MONO (-3645 3237);
FORCEPROP 1 LASTPIN (-3650 3075) $PN 2
J 0
(-3645 3085);
DISPLAY 0.787234 (-3645 3085);
PAINT MONO (-3645 3085);
FORCEPROP 1 LAST PACK_TYPE 0402LF
J 0
(-3600 3050);
DISPLAY 0.489362 (-3600 3050);
PAINT SKYBLUE (-3600 3050);
FORCEPROP 1 LAST MATERIAL EMPTY
J 0
(-3610 3100);
DISPLAY 0.489362 (-3610 3100);
PAINT SKYBLUE (-3610 3100);
FORCEPROP 1 LAST VALUE 1K
J 0
(-3605 3250);
DISPLAY 0.489362 (-3605 3250);
PAINT SKYBLUE (-3605 3250);
FORCEPROP 1 LAST WATTAGE 1/16W
J 0
(-3610 3150);
DISPLAY 0.489362 (-3610 3150);
PAINT SKYBLUE (-3610 3150);
FORCEPROP 1 LAST TOLERANCE 1%
J 0
(-3605 3200);
DISPLAY 0.489362 (-3605 3200);
PAINT SKYBLUE (-3605 3200);
FORCEPROP 2 LAST CDS_LIB pure_quanta
J 0
(-3650 3175);
DISPLAY INVISIBLE (-3650 3175);
FORCEPROP 1 LAST PATH I152
J 0
(-3600 3350);
DISPLAY 0.978723 (-3600 3350);
PAINT WHITE (-3600 3350);
DISPLAY INVISIBLE (-3600 3350);
FORCEPROP 1 LAST PART_NUMBER CS21002FB06
J 0
(-3610 3050);
DISPLAY 0.489362 (-3610 3050);
PAINT SKYBLUE (-3610 3050);
DISPLAY INVISIBLE (-3610 3050);
FORCEADD VCC_CORE..1
(-3450 3450);
FORCEPROP 3 LASTPIN (-3450 3400) SIG_NAME PVDD11_S3_P1\g
J 0
(-3440 3410);
DISPLAY 0.659574 (-3440 3410);
PAINT MONO (-3440 3410);
DISPLAY INVISIBLE (-3440 3410);
FORCEPROP 1 LAST HDL_POWER PVDD11_S3_P1
J 1
(-3450 3500);
DISPLAY 0.489362 (-3450 3500);
PAINT GREEN (-3450 3500);
FORCEPROP 2 LAST CDS_LIB pure_quanta_power
J 0
(-3450 3450);
DISPLAY INVISIBLE (-3450 3450);
FORCEPROP 1 LAST PATH I153
J 0
(-3400 3475);
DISPLAY 0.872340 (-3400 3475);
PAINT AQUA (-3400 3475);
DISPLAY INVISIBLE (-3400 3475);
FORCEADD Q_RES..2
(-3650 1725);
FORCEPROP 1 LAST LOCATION R5013
J 0
(-3605 1850);
DISPLAY 0.489362 (-3605 1850);
PAINT SKYBLUE (-3605 1850);
FORCEPROP 0 LAST $SEC 1
J 0
(-3600 1875);
DISPLAY 0.680851 (-3600 1875);
PAINT MONO (-3600 1875);
DISPLAY INVISIBLE (-3600 1875);
FORCEPROP 0 LAST CDS_SEC 1
J 0
(-3600 1875);
DISPLAY 0.680851 (-3600 1875);
DISPLAY INVISIBLE (-3600 1875);
FORCEPROP 1 LASTPIN (-3650 1825) $PN 1
J 0
(-3645 1787);
DISPLAY 0.787234 (-3645 1787);
PAINT MONO (-3645 1787);
FORCEPROP 1 LASTPIN (-3650 1625) $PN 2
J 0
(-3645 1635);
DISPLAY 0.787234 (-3645 1635);
PAINT MONO (-3645 1635);
FORCEPROP 1 LAST TOLERANCE 1%
J 0
(-3605 1750);
DISPLAY 0.489362 (-3605 1750);
PAINT SKYBLUE (-3605 1750);
FORCEPROP 1 LAST VALUE 1K
J 0
(-3605 1800);
DISPLAY 0.489362 (-3605 1800);
PAINT SKYBLUE (-3605 1800);
FORCEPROP 1 LAST MATERIAL EMPTY
J 0
(-3610 1650);
DISPLAY 0.489362 (-3610 1650);
PAINT SKYBLUE (-3610 1650);
FORCEPROP 1 LAST WATTAGE 1/16W
J 0
(-3610 1700);
DISPLAY 0.489362 (-3610 1700);
PAINT SKYBLUE (-3610 1700);
FORCEPROP 1 LAST PACK_TYPE 0402LF
J 0
(-3600 1600);
DISPLAY 0.489362 (-3600 1600);
PAINT SKYBLUE (-3600 1600);
FORCEPROP 2 LAST CDS_LIB pure_quanta
J 0
(-3650 1725);
DISPLAY INVISIBLE (-3650 1725);
FORCEPROP 1 LAST PATH I154
J 0
(-3600 1900);
DISPLAY 0.978723 (-3600 1900);
PAINT WHITE (-3600 1900);
DISPLAY INVISIBLE (-3600 1900);
FORCEPROP 1 LAST PART_NUMBER CS21002FB06
J 0
(-3610 1600);
DISPLAY 0.489362 (-3610 1600);
PAINT SKYBLUE (-3610 1600);
DISPLAY INVISIBLE (-3610 1600);
FORCEADD VCC_CORE..1
(-3450 2000);
FORCEPROP 3 LASTPIN (-3450 1950) SIG_NAME PVDD11_S3_P1\g
J 0
(-3440 1960);
DISPLAY 0.659574 (-3440 1960);
PAINT MONO (-3440 1960);
DISPLAY INVISIBLE (-3440 1960);
FORCEPROP 1 LAST HDL_POWER PVDD11_S3_P1
J 1
(-3450 2050);
DISPLAY 0.489362 (-3450 2050);
PAINT GREEN (-3450 2050);
FORCEPROP 2 LAST CDS_LIB pure_quanta_power
J 0
(-3450 2000);
DISPLAY INVISIBLE (-3450 2000);
FORCEPROP 1 LAST PATH I155
J 0
(-3400 2025);
DISPLAY 0.872340 (-3400 2025);
PAINT AQUA (-3400 2025);
DISPLAY INVISIBLE (-3400 2025);
FORCEADD Q_RES..2
(-3450 1725);
FORCEPROP 1 LAST LOCATION R5012
J 0
(-3405 1850);
DISPLAY 0.489362 (-3405 1850);
PAINT SKYBLUE (-3405 1850);
FORCEPROP 0 LAST $SEC 1
J 0
(-3400 1875);
DISPLAY 0.680851 (-3400 1875);
PAINT MONO (-3400 1875);
DISPLAY INVISIBLE (-3400 1875);
FORCEPROP 0 LAST CDS_SEC 1
J 0
(-3400 1875);
DISPLAY 0.680851 (-3400 1875);
DISPLAY INVISIBLE (-3400 1875);
FORCEPROP 1 LASTPIN (-3450 1825) $PN 1
J 0
(-3445 1787);
DISPLAY 0.787234 (-3445 1787);
PAINT MONO (-3445 1787);
FORCEPROP 1 LASTPIN (-3450 1625) $PN 2
J 0
(-3445 1635);
DISPLAY 0.787234 (-3445 1635);
PAINT MONO (-3445 1635);
FORCEPROP 1 LAST PACK_TYPE 0402LF
J 0
(-3400 1600);
DISPLAY 0.489362 (-3400 1600);
PAINT SKYBLUE (-3400 1600);
FORCEPROP 1 LAST VALUE 1K
J 0
(-3405 1800);
DISPLAY 0.489362 (-3405 1800);
PAINT SKYBLUE (-3405 1800);
FORCEPROP 1 LAST MATERIAL EMPTY
J 0
(-3410 1650);
DISPLAY 0.489362 (-3410 1650);
PAINT SKYBLUE (-3410 1650);
FORCEPROP 1 LAST TOLERANCE 1%
J 0
(-3405 1750);
DISPLAY 0.489362 (-3405 1750);
PAINT SKYBLUE (-3405 1750);
FORCEPROP 1 LAST WATTAGE 1/16W
J 0
(-3410 1700);
DISPLAY 0.489362 (-3410 1700);
PAINT SKYBLUE (-3410 1700);
FORCEPROP 2 LAST CDS_LIB pure_quanta
J 0
(-3450 1725);
DISPLAY INVISIBLE (-3450 1725);
FORCEPROP 1 LAST PATH I156
J 0
(-3400 1900);
DISPLAY 0.978723 (-3400 1900);
PAINT WHITE (-3400 1900);
DISPLAY INVISIBLE (-3400 1900);
FORCEPROP 1 LAST PART_NUMBER CS21002FB06
J 0
(-3410 1600);
DISPLAY 0.489362 (-3410 1600);
PAINT SKYBLUE (-3410 1600);
DISPLAY INVISIBLE (-3410 1600);
FORCEADD Q_RES..2
(-5650 6175);
FORCEPROP 1 LAST LOCATION R5015
J 0
(-5605 6300);
DISPLAY 0.489362 (-5605 6300);
PAINT SKYBLUE (-5605 6300);
FORCEPROP 0 LAST $SEC 1
J 0
(-5600 6325);
DISPLAY 0.680851 (-5600 6325);
PAINT MONO (-5600 6325);
DISPLAY INVISIBLE (-5600 6325);
FORCEPROP 0 LAST CDS_SEC 1
J 0
(-5600 6325);
DISPLAY 0.680851 (-5600 6325);
DISPLAY INVISIBLE (-5600 6325);
FORCEPROP 1 LASTPIN (-5650 6275) $PN 1
J 0
(-5645 6237);
DISPLAY 0.787234 (-5645 6237);
PAINT MONO (-5645 6237);
FORCEPROP 1 LASTPIN (-5650 6075) $PN 2
J 0
(-5645 6085);
DISPLAY 0.787234 (-5645 6085);
PAINT MONO (-5645 6085);
FORCEPROP 1 LAST VALUE 1K
J 0
(-5605 6250);
DISPLAY 0.489362 (-5605 6250);
PAINT SKYBLUE (-5605 6250);
FORCEPROP 1 LAST TOLERANCE 1%
J 0
(-5605 6200);
DISPLAY 0.489362 (-5605 6200);
PAINT SKYBLUE (-5605 6200);
FORCEPROP 1 LAST MATERIAL EMPTY
J 0
(-5610 6100);
DISPLAY 0.489362 (-5610 6100);
PAINT RED (-5610 6100);
FORCEPROP 1 LAST WATTAGE 1/16W
J 0
(-5610 6150);
DISPLAY 0.489362 (-5610 6150);
PAINT SKYBLUE (-5610 6150);
FORCEPROP 1 LAST PACK_TYPE 0402LF
J 0
(-5600 6050);
DISPLAY 0.489362 (-5600 6050);
PAINT SKYBLUE (-5600 6050);
FORCEPROP 2 LAST CDS_LIB pure_quanta
J 0
(-5650 6175);
DISPLAY INVISIBLE (-5650 6175);
FORCEPROP 1 LAST PATH I157
J 0
(-5600 6350);
DISPLAY 0.978723 (-5600 6350);
PAINT WHITE (-5600 6350);
DISPLAY INVISIBLE (-5600 6350);
FORCEPROP 1 LAST PART_NUMBER CS21002FB06
J 0
(-5610 6050);
DISPLAY 0.489362 (-5610 6050);
PAINT SKYBLUE (-5610 6050);
DISPLAY INVISIBLE (-5610 6050);
FORCEADD VCC_CORE..1
(-5450 6475);
FORCEPROP 3 LASTPIN (-5450 6425) SIG_NAME PVDD11_S3_P0\g
J 0
(-5440 6435);
DISPLAY 0.659574 (-5440 6435);
PAINT MONO (-5440 6435);
DISPLAY INVISIBLE (-5440 6435);
FORCEPROP 1 LAST HDL_POWER PVDD11_S3_P0
J 1
(-5450 6525);
DISPLAY 0.489362 (-5450 6525);
PAINT GREEN (-5450 6525);
FORCEPROP 2 LAST CDS_LIB pure_quanta_power
J 0
(-5450 6475);
DISPLAY INVISIBLE (-5450 6475);
FORCEPROP 1 LAST PATH I158
J 0
(-5400 6500);
DISPLAY 0.872340 (-5400 6500);
PAINT AQUA (-5400 6500);
DISPLAY INVISIBLE (-5400 6500);
FORCEADD Q_RES..2
(-5450 6175);
FORCEPROP 1 LAST LOCATION R5014
J 0
(-5405 6300);
DISPLAY 0.489362 (-5405 6300);
PAINT SKYBLUE (-5405 6300);
FORCEPROP 0 LAST $SEC 1
J 0
(-5400 6325);
DISPLAY 0.680851 (-5400 6325);
PAINT MONO (-5400 6325);
DISPLAY INVISIBLE (-5400 6325);
FORCEPROP 0 LAST CDS_SEC 1
J 0
(-5400 6325);
DISPLAY 0.680851 (-5400 6325);
DISPLAY INVISIBLE (-5400 6325);
FORCEPROP 1 LASTPIN (-5450 6275) $PN 1
J 0
(-5445 6237);
DISPLAY 0.787234 (-5445 6237);
PAINT MONO (-5445 6237);
FORCEPROP 1 LASTPIN (-5450 6075) $PN 2
J 0
(-5445 6085);
DISPLAY 0.787234 (-5445 6085);
PAINT MONO (-5445 6085);
FORCEPROP 1 LAST VALUE 1K
J 0
(-5405 6250);
DISPLAY 0.489362 (-5405 6250);
PAINT SKYBLUE (-5405 6250);
FORCEPROP 1 LAST MATERIAL EMPTY
J 0
(-5410 6100);
DISPLAY 0.489362 (-5410 6100);
PAINT RED (-5410 6100);
FORCEPROP 1 LAST WATTAGE 1/16W
J 0
(-5410 6150);
DISPLAY 0.489362 (-5410 6150);
PAINT SKYBLUE (-5410 6150);
FORCEPROP 1 LAST PACK_TYPE 0402LF
J 0
(-5400 6050);
DISPLAY 0.489362 (-5400 6050);
PAINT SKYBLUE (-5400 6050);
FORCEPROP 1 LAST TOLERANCE 1%
J 0
(-5405 6200);
DISPLAY 0.489362 (-5405 6200);
PAINT SKYBLUE (-5405 6200);
FORCEPROP 2 LAST CDS_LIB pure_quanta
J 0
(-5450 6175);
DISPLAY INVISIBLE (-5450 6175);
FORCEPROP 1 LAST PATH I159
J 0
(-5400 6350);
DISPLAY 0.978723 (-5400 6350);
PAINT WHITE (-5400 6350);
DISPLAY INVISIBLE (-5400 6350);
FORCEPROP 1 LAST PART_NUMBER CS21002FB06
J 0
(-5410 6050);
DISPLAY 0.489362 (-5410 6050);
PAINT SKYBLUE (-5410 6050);
DISPLAY INVISIBLE (-5410 6050);
FORCEADD VCC_CORE..1
(-5450 4900);
FORCEPROP 3 LASTPIN (-5450 4850) SIG_NAME PVDD11_S3_P0\g
J 0
(-5440 4860);
DISPLAY 0.659574 (-5440 4860);
PAINT MONO (-5440 4860);
DISPLAY INVISIBLE (-5440 4860);
FORCEPROP 1 LAST HDL_POWER PVDD11_S3_P0
J 1
(-5450 4950);
DISPLAY 0.489362 (-5450 4950);
PAINT GREEN (-5450 4950);
FORCEPROP 2 LAST CDS_LIB pure_quanta_power
J 0
(-5450 4900);
DISPLAY INVISIBLE (-5450 4900);
FORCEPROP 1 LAST PATH I160
J 0
(-5400 4925);
DISPLAY 0.872340 (-5400 4925);
PAINT AQUA (-5400 4925);
DISPLAY INVISIBLE (-5400 4925);
FORCEADD Q_RES..2
(-5650 4700);
FORCEPROP 1 LAST LOCATION R5017
J 0
(-5605 4825);
DISPLAY 0.489362 (-5605 4825);
PAINT SKYBLUE (-5605 4825);
FORCEPROP 0 LAST $SEC 1
J 0
(-5600 4850);
DISPLAY 0.680851 (-5600 4850);
PAINT MONO (-5600 4850);
DISPLAY INVISIBLE (-5600 4850);
FORCEPROP 0 LAST CDS_SEC 1
J 0
(-5600 4850);
DISPLAY 0.680851 (-5600 4850);
DISPLAY INVISIBLE (-5600 4850);
FORCEPROP 1 LASTPIN (-5650 4800) $PN 1
J 0
(-5645 4762);
DISPLAY 0.787234 (-5645 4762);
PAINT MONO (-5645 4762);
FORCEPROP 1 LASTPIN (-5650 4600) $PN 2
J 0
(-5645 4610);
DISPLAY 0.787234 (-5645 4610);
PAINT MONO (-5645 4610);
FORCEPROP 1 LAST WATTAGE 1/16W
J 0
(-5610 4675);
DISPLAY 0.489362 (-5610 4675);
PAINT SKYBLUE (-5610 4675);
FORCEPROP 1 LAST VALUE 1K
J 0
(-5605 4775);
DISPLAY 0.489362 (-5605 4775);
PAINT SKYBLUE (-5605 4775);
FORCEPROP 1 LAST TOLERANCE 1%
J 0
(-5605 4725);
DISPLAY 0.489362 (-5605 4725);
PAINT SKYBLUE (-5605 4725);
FORCEPROP 1 LAST PACK_TYPE 0402LF
J 0
(-5600 4575);
DISPLAY 0.489362 (-5600 4575);
PAINT SKYBLUE (-5600 4575);
FORCEPROP 1 LAST MATERIAL EMPTY
J 0
(-5610 4625);
DISPLAY 0.489362 (-5610 4625);
PAINT RED (-5610 4625);
FORCEPROP 2 LAST CDS_LIB pure_quanta
J 0
(-5650 4700);
DISPLAY INVISIBLE (-5650 4700);
FORCEPROP 1 LAST PATH I161
J 0
(-5600 4875);
DISPLAY 0.978723 (-5600 4875);
PAINT WHITE (-5600 4875);
DISPLAY INVISIBLE (-5600 4875);
FORCEPROP 1 LAST PART_NUMBER CS21002FB06
J 0
(-5610 4575);
DISPLAY 0.489362 (-5610 4575);
PAINT SKYBLUE (-5610 4575);
DISPLAY INVISIBLE (-5610 4575);
FORCEADD Q_RES..2
(-5450 4700);
FORCEPROP 1 LAST LOCATION R5016
J 0
(-5405 4825);
DISPLAY 0.489362 (-5405 4825);
PAINT SKYBLUE (-5405 4825);
FORCEPROP 0 LAST $SEC 1
J 0
(-5400 4850);
DISPLAY 0.680851 (-5400 4850);
PAINT MONO (-5400 4850);
DISPLAY INVISIBLE (-5400 4850);
FORCEPROP 0 LAST CDS_SEC 1
J 0
(-5400 4850);
DISPLAY 0.680851 (-5400 4850);
DISPLAY INVISIBLE (-5400 4850);
FORCEPROP 1 LASTPIN (-5450 4800) $PN 1
J 0
(-5445 4762);
DISPLAY 0.787234 (-5445 4762);
PAINT MONO (-5445 4762);
FORCEPROP 1 LASTPIN (-5450 4600) $PN 2
J 0
(-5445 4610);
DISPLAY 0.787234 (-5445 4610);
PAINT MONO (-5445 4610);
FORCEPROP 1 LAST TOLERANCE 1%
J 0
(-5405 4725);
DISPLAY 0.489362 (-5405 4725);
PAINT SKYBLUE (-5405 4725);
FORCEPROP 1 LAST VALUE 1K
J 0
(-5405 4775);
DISPLAY 0.489362 (-5405 4775);
PAINT SKYBLUE (-5405 4775);
FORCEPROP 1 LAST PACK_TYPE 0402LF
J 0
(-5400 4575);
DISPLAY 0.489362 (-5400 4575);
PAINT SKYBLUE (-5400 4575);
FORCEPROP 1 LAST MATERIAL EMPTY
J 0
(-5410 4625);
DISPLAY 0.489362 (-5410 4625);
PAINT RED (-5410 4625);
FORCEPROP 1 LAST WATTAGE 1/16W
J 0
(-5410 4675);
DISPLAY 0.489362 (-5410 4675);
PAINT SKYBLUE (-5410 4675);
FORCEPROP 2 LAST CDS_LIB pure_quanta
J 0
(-5450 4700);
DISPLAY INVISIBLE (-5450 4700);
FORCEPROP 1 LAST PATH I162
J 0
(-5400 4875);
DISPLAY 0.978723 (-5400 4875);
PAINT WHITE (-5400 4875);
DISPLAY INVISIBLE (-5400 4875);
FORCEPROP 1 LAST PART_NUMBER CS21002FB06
J 0
(-5410 4575);
DISPLAY 0.489362 (-5410 4575);
PAINT SKYBLUE (-5410 4575);
DISPLAY INVISIBLE (-5410 4575);
FORCEADD Q_RES..2
(-5450 3175);
FORCEPROP 1 LAST LOCATION R5018
J 0
(-5405 3300);
DISPLAY 0.489362 (-5405 3300);
PAINT SKYBLUE (-5405 3300);
FORCEPROP 0 LAST $SEC 1
J 0
(-5400 3325);
DISPLAY 0.680851 (-5400 3325);
PAINT MONO (-5400 3325);
DISPLAY INVISIBLE (-5400 3325);
FORCEPROP 0 LAST CDS_SEC 1
J 0
(-5400 3325);
DISPLAY 0.680851 (-5400 3325);
DISPLAY INVISIBLE (-5400 3325);
FORCEPROP 1 LASTPIN (-5450 3275) $PN 1
J 0
(-5445 3237);
DISPLAY 0.787234 (-5445 3237);
PAINT MONO (-5445 3237);
FORCEPROP 1 LASTPIN (-5450 3075) $PN 2
J 0
(-5445 3085);
DISPLAY 0.787234 (-5445 3085);
PAINT MONO (-5445 3085);
FORCEPROP 1 LAST PACK_TYPE 0402LF
J 0
(-5400 3050);
DISPLAY 0.489362 (-5400 3050);
PAINT SKYBLUE (-5400 3050);
FORCEPROP 1 LAST VALUE 1K
J 0
(-5405 3250);
DISPLAY 0.489362 (-5405 3250);
PAINT SKYBLUE (-5405 3250);
FORCEPROP 1 LAST TOLERANCE 1%
J 0
(-5405 3200);
DISPLAY 0.489362 (-5405 3200);
PAINT SKYBLUE (-5405 3200);
FORCEPROP 1 LAST WATTAGE 1/16W
J 0
(-5410 3150);
DISPLAY 0.489362 (-5410 3150);
PAINT SKYBLUE (-5410 3150);
FORCEPROP 1 LAST MATERIAL EMPTY
J 0
(-5410 3100);
DISPLAY 0.489362 (-5410 3100);
PAINT RED (-5410 3100);
FORCEPROP 2 LAST CDS_LIB pure_quanta
J 0
(-5450 3175);
DISPLAY INVISIBLE (-5450 3175);
FORCEPROP 1 LAST PATH I163
J 0
(-5400 3350);
DISPLAY 0.978723 (-5400 3350);
PAINT WHITE (-5400 3350);
DISPLAY INVISIBLE (-5400 3350);
FORCEPROP 1 LAST PART_NUMBER CS21002FB06
J 0
(-5410 3050);
DISPLAY 0.489362 (-5410 3050);
PAINT SKYBLUE (-5410 3050);
DISPLAY INVISIBLE (-5410 3050);
FORCEADD Q_RES..2
(-5650 3175);
FORCEPROP 1 LAST LOCATION R5019
J 0
(-5605 3300);
DISPLAY 0.489362 (-5605 3300);
PAINT SKYBLUE (-5605 3300);
FORCEPROP 0 LAST $SEC 1
J 0
(-5600 3325);
DISPLAY 0.680851 (-5600 3325);
PAINT MONO (-5600 3325);
DISPLAY INVISIBLE (-5600 3325);
FORCEPROP 0 LAST CDS_SEC 1
J 0
(-5600 3325);
DISPLAY 0.680851 (-5600 3325);
DISPLAY INVISIBLE (-5600 3325);
FORCEPROP 1 LASTPIN (-5650 3275) $PN 1
J 0
(-5645 3237);
DISPLAY 0.787234 (-5645 3237);
PAINT MONO (-5645 3237);
FORCEPROP 1 LASTPIN (-5650 3075) $PN 2
J 0
(-5645 3085);
DISPLAY 0.787234 (-5645 3085);
PAINT MONO (-5645 3085);
FORCEPROP 1 LAST VALUE 1K
J 0
(-5605 3250);
DISPLAY 0.489362 (-5605 3250);
PAINT SKYBLUE (-5605 3250);
FORCEPROP 1 LAST TOLERANCE 1%
J 0
(-5605 3200);
DISPLAY 0.489362 (-5605 3200);
PAINT SKYBLUE (-5605 3200);
FORCEPROP 1 LAST WATTAGE 1/16W
J 0
(-5610 3150);
DISPLAY 0.489362 (-5610 3150);
PAINT SKYBLUE (-5610 3150);
FORCEPROP 1 LAST MATERIAL EMPTY
J 0
(-5610 3100);
DISPLAY 0.489362 (-5610 3100);
PAINT RED (-5610 3100);
FORCEPROP 1 LAST PACK_TYPE 0402LF
J 0
(-5600 3050);
DISPLAY 0.489362 (-5600 3050);
PAINT SKYBLUE (-5600 3050);
FORCEPROP 2 LAST CDS_LIB pure_quanta
J 0
(-5650 3175);
DISPLAY INVISIBLE (-5650 3175);
FORCEPROP 1 LAST PATH I164
J 0
(-5600 3350);
DISPLAY 0.978723 (-5600 3350);
PAINT WHITE (-5600 3350);
DISPLAY INVISIBLE (-5600 3350);
FORCEPROP 1 LAST PART_NUMBER CS21002FB06
J 0
(-5610 3050);
DISPLAY 0.489362 (-5610 3050);
PAINT SKYBLUE (-5610 3050);
DISPLAY INVISIBLE (-5610 3050);
FORCEADD VCC_CORE..1
(-5450 3375);
FORCEPROP 3 LASTPIN (-5450 3325) SIG_NAME PVDD11_S3_P1\g
J 0
(-5440 3335);
DISPLAY 0.659574 (-5440 3335);
PAINT MONO (-5440 3335);
DISPLAY INVISIBLE (-5440 3335);
FORCEPROP 1 LAST HDL_POWER PVDD11_S3_P1
J 1
(-5450 3425);
DISPLAY 0.489362 (-5450 3425);
PAINT GREEN (-5450 3425);
FORCEPROP 2 LAST CDS_LIB pure_quanta_power
J 0
(-5450 3375);
DISPLAY INVISIBLE (-5450 3375);
FORCEPROP 1 LAST PATH I165
J 0
(-5400 3400);
DISPLAY 0.872340 (-5400 3400);
PAINT AQUA (-5400 3400);
DISPLAY INVISIBLE (-5400 3400);
FORCEADD Q_RES..2
(-5650 1725);
FORCEPROP 1 LAST LOCATION R5021
J 0
(-5605 1850);
DISPLAY 0.489362 (-5605 1850);
PAINT SKYBLUE (-5605 1850);
FORCEPROP 0 LAST $SEC 1
J 0
(-5600 1875);
DISPLAY 0.680851 (-5600 1875);
PAINT MONO (-5600 1875);
DISPLAY INVISIBLE (-5600 1875);
FORCEPROP 0 LAST CDS_SEC 1
J 0
(-5600 1875);
DISPLAY 0.680851 (-5600 1875);
DISPLAY INVISIBLE (-5600 1875);
FORCEPROP 1 LASTPIN (-5650 1825) $PN 1
J 0
(-5645 1787);
DISPLAY 0.787234 (-5645 1787);
PAINT MONO (-5645 1787);
FORCEPROP 1 LASTPIN (-5650 1625) $PN 2
J 0
(-5645 1635);
DISPLAY 0.787234 (-5645 1635);
PAINT MONO (-5645 1635);
FORCEPROP 1 LAST TOLERANCE 1%
J 0
(-5605 1750);
DISPLAY 0.489362 (-5605 1750);
PAINT SKYBLUE (-5605 1750);
FORCEPROP 1 LAST VALUE 1K
J 0
(-5605 1800);
DISPLAY 0.489362 (-5605 1800);
PAINT SKYBLUE (-5605 1800);
FORCEPROP 1 LAST MATERIAL EMPTY
J 0
(-5610 1650);
DISPLAY 0.489362 (-5610 1650);
PAINT RED (-5610 1650);
FORCEPROP 1 LAST WATTAGE 1/16W
J 0
(-5610 1700);
DISPLAY 0.489362 (-5610 1700);
PAINT SKYBLUE (-5610 1700);
FORCEPROP 1 LAST PACK_TYPE 0402LF
J 0
(-5600 1600);
DISPLAY 0.489362 (-5600 1600);
PAINT SKYBLUE (-5600 1600);
FORCEPROP 2 LAST CDS_LIB pure_quanta
J 0
(-5650 1725);
DISPLAY INVISIBLE (-5650 1725);
FORCEPROP 1 LAST PATH I166
J 0
(-5600 1900);
DISPLAY 0.978723 (-5600 1900);
PAINT WHITE (-5600 1900);
DISPLAY INVISIBLE (-5600 1900);
FORCEPROP 1 LAST PART_NUMBER CS21002FB06
J 0
(-5610 1600);
DISPLAY 0.489362 (-5610 1600);
PAINT SKYBLUE (-5610 1600);
DISPLAY INVISIBLE (-5610 1600);
FORCEADD Q_RES..2
(-5450 1725);
FORCEPROP 1 LAST LOCATION R5020
J 0
(-5405 1850);
DISPLAY 0.489362 (-5405 1850);
PAINT SKYBLUE (-5405 1850);
FORCEPROP 0 LAST $SEC 1
J 0
(-5400 1875);
DISPLAY 0.680851 (-5400 1875);
PAINT MONO (-5400 1875);
DISPLAY INVISIBLE (-5400 1875);
FORCEPROP 0 LAST CDS_SEC 1
J 0
(-5400 1875);
DISPLAY 0.680851 (-5400 1875);
DISPLAY INVISIBLE (-5400 1875);
FORCEPROP 1 LASTPIN (-5450 1825) $PN 1
J 0
(-5445 1787);
DISPLAY 0.787234 (-5445 1787);
PAINT MONO (-5445 1787);
FORCEPROP 1 LASTPIN (-5450 1625) $PN 2
J 0
(-5445 1635);
DISPLAY 0.787234 (-5445 1635);
PAINT MONO (-5445 1635);
FORCEPROP 1 LAST TOLERANCE 1%
J 0
(-5405 1750);
DISPLAY 0.489362 (-5405 1750);
PAINT SKYBLUE (-5405 1750);
FORCEPROP 1 LAST VALUE 1K
J 0
(-5405 1800);
DISPLAY 0.489362 (-5405 1800);
PAINT SKYBLUE (-5405 1800);
FORCEPROP 1 LAST PACK_TYPE 0402LF
J 0
(-5400 1600);
DISPLAY 0.489362 (-5400 1600);
PAINT SKYBLUE (-5400 1600);
FORCEPROP 1 LAST MATERIAL EMPTY
J 0
(-5410 1650);
DISPLAY 0.489362 (-5410 1650);
PAINT RED (-5410 1650);
FORCEPROP 1 LAST WATTAGE 1/16W
J 0
(-5410 1700);
DISPLAY 0.489362 (-5410 1700);
PAINT SKYBLUE (-5410 1700);
FORCEPROP 2 LAST CDS_LIB pure_quanta
J 0
(-5450 1725);
DISPLAY INVISIBLE (-5450 1725);
FORCEPROP 1 LAST PATH I167
J 0
(-5400 1900);
DISPLAY 0.978723 (-5400 1900);
PAINT WHITE (-5400 1900);
DISPLAY INVISIBLE (-5400 1900);
FORCEPROP 1 LAST PART_NUMBER CS21002FB06
J 0
(-5410 1600);
DISPLAY 0.489362 (-5410 1600);
PAINT SKYBLUE (-5410 1600);
DISPLAY INVISIBLE (-5410 1600);
FORCEADD VCC_CORE..1
(-5450 1925);
FORCEPROP 3 LASTPIN (-5450 1875) SIG_NAME PVDD11_S3_P1\g
J 0
(-5440 1885);
DISPLAY 0.659574 (-5440 1885);
PAINT MONO (-5440 1885);
DISPLAY INVISIBLE (-5440 1885);
FORCEPROP 1 LAST HDL_POWER PVDD11_S3_P1
J 1
(-5450 1975);
DISPLAY 0.489362 (-5450 1975);
PAINT GREEN (-5450 1975);
FORCEPROP 2 LAST CDS_LIB pure_quanta_power
J 0
(-5450 1925);
DISPLAY INVISIBLE (-5450 1925);
FORCEPROP 1 LAST PATH I168
J 0
(-5400 1950);
DISPLAY 0.872340 (-5400 1950);
PAINT AQUA (-5400 1950);
DISPLAY INVISIBLE (-5400 1950);
FORCEADD OFFPAGE..3
R 2
(-6000 4225);
FORCEPROP 2 LAST $XR0 150 
J 0
(-6280 4225);
DISPLAY 0.638298 (-6280 4225);
PAINT MONO (-6280 4225);
FORCEPROP 2 LAST CDS_LIB standard
J 2
(-6000 4225);
DISPLAY INVISIBLE (-6000 4225);
FORCEPROP 1 LAST OFFPAGE TRUE
J 2
(-6325 4100);
DISPLAY 0.872340 (-6325 4100);
PAINT GREEN (-6325 4100);
DISPLAY INVISIBLE (-6325 4100);
FORCEPROP 1 LAST COMMENT_BODY TRUE
J 2
(-5950 4125);
DISPLAY 0.872340 (-5950 4125);
PAINT GREEN (-5950 4125);
DISPLAY INVISIBLE (-5950 4125);
FORCEPROP 2 LAST PATH I19
J 0
(-5950 4300);
DISPLAY 1.021277 (-5950 4300);
DISPLAY INVISIBLE (-5950 4300);
FORCEADD OFFPAGE..1
(-6000 4275);
FORCEPROP 2 LAST $XR0 150 
J 0
(-6282 4275);
DISPLAY 0.638298 (-6282 4275);
PAINT MONO (-6282 4275);
FORCEPROP 2 LAST CDS_LIB standard
J 0
(-6000 4275);
DISPLAY INVISIBLE (-6000 4275);
FORCEPROP 1 LAST OFFPAGE TRUE
J 0
(-5675 4150);
DISPLAY 0.872340 (-5675 4150);
PAINT GREEN (-5675 4150);
DISPLAY INVISIBLE (-5675 4150);
FORCEPROP 1 LAST COMMENT_BODY TRUE
J 0
(-5875 4175);
DISPLAY 0.872340 (-5875 4175);
PAINT GREEN (-5875 4175);
DISPLAY INVISIBLE (-5875 4175);
FORCEPROP 2 LAST PATH I20
J 0
(-5950 4350);
DISPLAY 1.021277 (-5950 4350);
DISPLAY INVISIBLE (-5950 4350);
FORCEADD OFFPAGE..3
R 2
(-5925 1250);
FORCEPROP 2 LAST $XR0 150 
J 0
(-6235 1250);
DISPLAY 0.638298 (-6235 1250);
PAINT MONO (-6235 1250);
FORCEPROP 2 LAST CDS_LIB standard
J 2
(-5925 1250);
DISPLAY INVISIBLE (-5925 1250);
FORCEPROP 1 LAST OFFPAGE TRUE
J 2
(-6250 1125);
DISPLAY 0.872340 (-6250 1125);
PAINT GREEN (-6250 1125);
DISPLAY INVISIBLE (-6250 1125);
FORCEPROP 1 LAST COMMENT_BODY TRUE
J 2
(-5875 1150);
DISPLAY 0.872340 (-5875 1150);
PAINT GREEN (-5875 1150);
DISPLAY INVISIBLE (-5875 1150);
FORCEPROP 2 LAST PATH I26
J 0
(-5875 1325);
DISPLAY 1.021277 (-5875 1325);
DISPLAY INVISIBLE (-5875 1325);
FORCEADD OFFPAGE..3
R 2
(-6000 2700);
FORCEPROP 2 LAST $XR0 150 
J 0
(-6280 2700);
DISPLAY 0.638298 (-6280 2700);
PAINT MONO (-6280 2700);
FORCEPROP 2 LAST CDS_LIB standard
J 2
(-6000 2700);
DISPLAY INVISIBLE (-6000 2700);
FORCEPROP 1 LAST OFFPAGE TRUE
J 2
(-6325 2575);
DISPLAY 0.872340 (-6325 2575);
PAINT GREEN (-6325 2575);
DISPLAY INVISIBLE (-6325 2575);
FORCEPROP 1 LAST COMMENT_BODY TRUE
J 2
(-5950 2600);
DISPLAY 0.872340 (-5950 2600);
PAINT GREEN (-5950 2600);
DISPLAY INVISIBLE (-5950 2600);
FORCEPROP 2 LAST PATH I28
J 0
(-5950 2775);
DISPLAY 1.021277 (-5950 2775);
DISPLAY INVISIBLE (-5950 2775);
FORCEADD OFFPAGE..1
(-5925 1300);
FORCEPROP 2 LAST $XR0 150 
J 0
(-6177 1300);
DISPLAY 0.638298 (-6177 1300);
PAINT MONO (-6177 1300);
FORCEPROP 2 LAST CDS_LIB standard
J 0
(-5925 1300);
DISPLAY INVISIBLE (-5925 1300);
FORCEPROP 1 LAST OFFPAGE TRUE
J 0
(-5600 1175);
DISPLAY 0.872340 (-5600 1175);
PAINT GREEN (-5600 1175);
DISPLAY INVISIBLE (-5600 1175);
FORCEPROP 1 LAST COMMENT_BODY TRUE
J 0
(-5800 1200);
DISPLAY 0.872340 (-5800 1200);
PAINT GREEN (-5800 1200);
DISPLAY INVISIBLE (-5800 1200);
FORCEPROP 2 LAST PATH I29
J 0
(-5875 1375);
DISPLAY 1.021277 (-5875 1375);
DISPLAY INVISIBLE (-5875 1375);
FORCEADD OFFPAGE..1
(-6000 2750);
FORCEPROP 2 LAST $XR0 150 
J 0
(-6282 2750);
DISPLAY 0.638298 (-6282 2750);
PAINT MONO (-6282 2750);
FORCEPROP 2 LAST CDS_LIB standard
J 0
(-6000 2750);
DISPLAY INVISIBLE (-6000 2750);
FORCEPROP 1 LAST OFFPAGE TRUE
J 0
(-5675 2625);
DISPLAY 0.872340 (-5675 2625);
PAINT GREEN (-5675 2625);
DISPLAY INVISIBLE (-5675 2625);
FORCEPROP 1 LAST COMMENT_BODY TRUE
J 0
(-5875 2650);
DISPLAY 0.872340 (-5875 2650);
PAINT GREEN (-5875 2650);
DISPLAY INVISIBLE (-5875 2650);
FORCEPROP 2 LAST PATH I30
J 0
(-5950 2825);
DISPLAY 1.021277 (-5950 2825);
DISPLAY INVISIBLE (-5950 2825);
FORCEADD Q_RES..1
R 2
(-3150 5875);
FORCEPROP 1 LAST LOCATION R1297
J 2
(-3300 5875);
DISPLAY 0.489362 (-3300 5875);
PAINT SKYBLUE (-3300 5875);
FORCEPROP 0 LAST $SEC 1
J 0
(-3300 5925);
DISPLAY 0.680851 (-3300 5925);
PAINT MONO (-3300 5925);
DISPLAY INVISIBLE (-3300 5925);
FORCEPROP 0 LAST CDS_SEC 1
J 0
(-3300 5925);
DISPLAY 1.021277 (-3300 5925);
DISPLAY INVISIBLE (-3300 5925);
FORCEPROP 1 LASTPIN (-3050 5875) $PN 1
J 2
(-3062 5887);
DISPLAY 0.489362 (-3062 5887);
PAINT MONO (-3062 5887);
FORCEPROP 1 LASTPIN (-3250 5875) $PN 2
J 2
(-3212 5887);
DISPLAY 0.489362 (-3212 5887);
PAINT MONO (-3212 5887);
FORCEPROP 1 LAST VALUE 0
J 0
(-3050 5875);
DISPLAY 0.489362 (-3050 5875);
PAINT SKYBLUE (-3050 5875);
FORCEPROP 2 LAST CDS_LIB pure_quanta
J 0
(-3150 5875);
DISPLAY INVISIBLE (-3150 5875);
FORCEPROP 1 LAST WATTAGE 1/16W
J 0
(-3550 5800);
DISPLAY 0.489362 (-3550 5800);
PAINT SKYBLUE (-3550 5800);
DISPLAY INVISIBLE (-3550 5800);
FORCEPROP 1 LAST MATERIAL CHIP
J 2
(-3575 5800);
DISPLAY 0.489362 (-3575 5800);
PAINT SKYBLUE (-3575 5800);
DISPLAY INVISIBLE (-3575 5800);
FORCEPROP 1 LAST TOLERANCE 5%
J 2
(-3125 5800);
DISPLAY 0.489362 (-3125 5800);
PAINT SKYBLUE (-3125 5800);
DISPLAY INVISIBLE (-3125 5800);
FORCEPROP 1 LAST PACK_TYPE 0402LF
J 2
(-3200 5800);
DISPLAY 0.489362 (-3200 5800);
PAINT SKYBLUE (-3200 5800);
DISPLAY INVISIBLE (-3200 5800);
FORCEPROP 1 LAST PATH I31
J 2
(-3100 6025);
DISPLAY 0.978723 (-3100 6025);
PAINT WHITE (-3100 6025);
DISPLAY INVISIBLE (-3100 6025);
FORCEPROP 1 LAST PART_NUMBER CS00002JB13
J 2
(-3175 5925);
DISPLAY 0.489362 (-3175 5925);
PAINT SKYBLUE (-3175 5925);
DISPLAY INVISIBLE (-3175 5925);
FORCEADD Q_RES..1
R 2
(-3150 5825);
FORCEPROP 1 LAST LOCATION R1298
J 2
(-3300 5825);
DISPLAY 0.489362 (-3300 5825);
PAINT SKYBLUE (-3300 5825);
FORCEPROP 0 LAST $SEC 1
J 0
(-3300 5875);
DISPLAY 0.680851 (-3300 5875);
PAINT MONO (-3300 5875);
DISPLAY INVISIBLE (-3300 5875);
FORCEPROP 0 LAST CDS_SEC 1
J 0
(-3300 5875);
DISPLAY 1.021277 (-3300 5875);
DISPLAY INVISIBLE (-3300 5875);
FORCEPROP 1 LASTPIN (-3050 5825) $PN 1
J 2
(-3062 5837);
DISPLAY 0.489362 (-3062 5837);
PAINT MONO (-3062 5837);
FORCEPROP 1 LASTPIN (-3250 5825) $PN 2
J 2
(-3212 5837);
DISPLAY 0.489362 (-3212 5837);
PAINT MONO (-3212 5837);
FORCEPROP 1 LAST VALUE 0
J 0
(-3050 5825);
DISPLAY 0.489362 (-3050 5825);
PAINT SKYBLUE (-3050 5825);
FORCEPROP 2 LAST CDS_LIB pure_quanta
J 0
(-3150 5825);
DISPLAY INVISIBLE (-3150 5825);
FORCEPROP 1 LAST WATTAGE 1/16W
J 0
(-3550 5750);
DISPLAY 0.489362 (-3550 5750);
PAINT SKYBLUE (-3550 5750);
DISPLAY INVISIBLE (-3550 5750);
FORCEPROP 1 LAST MATERIAL CHIP
J 2
(-3575 5750);
DISPLAY 0.489362 (-3575 5750);
PAINT SKYBLUE (-3575 5750);
DISPLAY INVISIBLE (-3575 5750);
FORCEPROP 1 LAST TOLERANCE 5%
J 2
(-3125 5750);
DISPLAY 0.489362 (-3125 5750);
PAINT SKYBLUE (-3125 5750);
DISPLAY INVISIBLE (-3125 5750);
FORCEPROP 1 LAST PACK_TYPE 0402LF
J 2
(-3200 5750);
DISPLAY 0.489362 (-3200 5750);
PAINT SKYBLUE (-3200 5750);
DISPLAY INVISIBLE (-3200 5750);
FORCEPROP 1 LAST PATH I32
J 2
(-3100 5975);
DISPLAY 0.978723 (-3100 5975);
PAINT WHITE (-3100 5975);
DISPLAY INVISIBLE (-3100 5975);
FORCEPROP 1 LAST PART_NUMBER CS00002JB13
J 2
(-3175 5875);
DISPLAY 0.489362 (-3175 5875);
PAINT SKYBLUE (-3175 5875);
DISPLAY INVISIBLE (-3175 5875);
FORCEADD Q_RES..1
R 2
(-3150 4475);
FORCEPROP 1 LAST LOCATION R1299
J 2
(-3300 4475);
DISPLAY 0.489362 (-3300 4475);
PAINT SKYBLUE (-3300 4475);
FORCEPROP 0 LAST $SEC 1
J 0
(-3300 4525);
DISPLAY 0.680851 (-3300 4525);
PAINT MONO (-3300 4525);
DISPLAY INVISIBLE (-3300 4525);
FORCEPROP 0 LAST CDS_SEC 1
J 0
(-3300 4525);
DISPLAY 1.021277 (-3300 4525);
DISPLAY INVISIBLE (-3300 4525);
FORCEPROP 1 LASTPIN (-3050 4475) $PN 1
J 2
(-3062 4487);
DISPLAY 0.489362 (-3062 4487);
PAINT MONO (-3062 4487);
FORCEPROP 1 LASTPIN (-3250 4475) $PN 2
J 2
(-3212 4487);
DISPLAY 0.489362 (-3212 4487);
PAINT MONO (-3212 4487);
FORCEPROP 1 LAST VALUE 0
J 0
(-3050 4475);
DISPLAY 0.489362 (-3050 4475);
PAINT SKYBLUE (-3050 4475);
FORCEPROP 2 LAST CDS_LIB pure_quanta
J 0
(-3150 4475);
DISPLAY INVISIBLE (-3150 4475);
FORCEPROP 1 LAST WATTAGE 1/16W
J 0
(-3550 4400);
DISPLAY 0.489362 (-3550 4400);
PAINT SKYBLUE (-3550 4400);
DISPLAY INVISIBLE (-3550 4400);
FORCEPROP 1 LAST MATERIAL CHIP
J 2
(-3575 4400);
DISPLAY 0.489362 (-3575 4400);
PAINT SKYBLUE (-3575 4400);
DISPLAY INVISIBLE (-3575 4400);
FORCEPROP 1 LAST TOLERANCE 5%
J 2
(-3125 4400);
DISPLAY 0.489362 (-3125 4400);
PAINT SKYBLUE (-3125 4400);
DISPLAY INVISIBLE (-3125 4400);
FORCEPROP 1 LAST PACK_TYPE 0402LF
J 2
(-3200 4400);
DISPLAY 0.489362 (-3200 4400);
PAINT SKYBLUE (-3200 4400);
DISPLAY INVISIBLE (-3200 4400);
FORCEPROP 1 LAST PATH I33
J 2
(-3100 4625);
DISPLAY 0.978723 (-3100 4625);
PAINT WHITE (-3100 4625);
DISPLAY INVISIBLE (-3100 4625);
FORCEPROP 1 LAST PART_NUMBER CS00002JB13
J 2
(-3175 4525);
DISPLAY 0.489362 (-3175 4525);
PAINT SKYBLUE (-3175 4525);
DISPLAY INVISIBLE (-3175 4525);
FORCEADD Q_RES..1
R 2
(-3150 4425);
FORCEPROP 1 LAST LOCATION R1300
J 2
(-3300 4425);
DISPLAY 0.489362 (-3300 4425);
PAINT SKYBLUE (-3300 4425);
FORCEPROP 0 LAST $SEC 1
J 0
(-3300 4475);
DISPLAY 0.680851 (-3300 4475);
PAINT MONO (-3300 4475);
DISPLAY INVISIBLE (-3300 4475);
FORCEPROP 0 LAST CDS_SEC 1
J 0
(-3300 4475);
DISPLAY 1.021277 (-3300 4475);
DISPLAY INVISIBLE (-3300 4475);
FORCEPROP 1 LASTPIN (-3050 4425) $PN 1
J 2
(-3062 4437);
DISPLAY 0.489362 (-3062 4437);
PAINT MONO (-3062 4437);
FORCEPROP 1 LASTPIN (-3250 4425) $PN 2
J 2
(-3212 4437);
DISPLAY 0.489362 (-3212 4437);
PAINT MONO (-3212 4437);
FORCEPROP 1 LAST VALUE 0
J 0
(-3050 4425);
DISPLAY 0.489362 (-3050 4425);
PAINT SKYBLUE (-3050 4425);
FORCEPROP 2 LAST CDS_LIB pure_quanta
J 0
(-3150 4425);
DISPLAY INVISIBLE (-3150 4425);
FORCEPROP 1 LAST WATTAGE 1/16W
J 0
(-3550 4350);
DISPLAY 0.489362 (-3550 4350);
PAINT SKYBLUE (-3550 4350);
DISPLAY INVISIBLE (-3550 4350);
FORCEPROP 1 LAST MATERIAL CHIP
J 2
(-3575 4350);
DISPLAY 0.489362 (-3575 4350);
PAINT SKYBLUE (-3575 4350);
DISPLAY INVISIBLE (-3575 4350);
FORCEPROP 1 LAST TOLERANCE 5%
J 2
(-3125 4350);
DISPLAY 0.489362 (-3125 4350);
PAINT SKYBLUE (-3125 4350);
DISPLAY INVISIBLE (-3125 4350);
FORCEPROP 1 LAST PACK_TYPE 0402LF
J 2
(-3200 4350);
DISPLAY 0.489362 (-3200 4350);
PAINT SKYBLUE (-3200 4350);
DISPLAY INVISIBLE (-3200 4350);
FORCEPROP 1 LAST PATH I34
J 2
(-3100 4575);
DISPLAY 0.978723 (-3100 4575);
PAINT WHITE (-3100 4575);
DISPLAY INVISIBLE (-3100 4575);
FORCEPROP 1 LAST PART_NUMBER CS00002JB13
J 2
(-3175 4475);
DISPLAY 0.489362 (-3175 4475);
PAINT SKYBLUE (-3175 4475);
DISPLAY INVISIBLE (-3175 4475);
FORCEADD Q_RES..1
R 2
(-3200 2950);
FORCEPROP 1 LAST LOCATION R1293
J 2
(-3350 2950);
DISPLAY 0.489362 (-3350 2950);
PAINT SKYBLUE (-3350 2950);
FORCEPROP 0 LAST $SEC 1
J 0
(-3350 3000);
DISPLAY 0.680851 (-3350 3000);
PAINT MONO (-3350 3000);
DISPLAY INVISIBLE (-3350 3000);
FORCEPROP 0 LAST CDS_SEC 1
J 0
(-3350 3000);
DISPLAY 1.021277 (-3350 3000);
DISPLAY INVISIBLE (-3350 3000);
FORCEPROP 1 LASTPIN (-3100 2950) $PN 1
J 2
(-3112 2962);
DISPLAY 0.489362 (-3112 2962);
PAINT MONO (-3112 2962);
FORCEPROP 1 LASTPIN (-3300 2950) $PN 2
J 2
(-3262 2962);
DISPLAY 0.489362 (-3262 2962);
PAINT MONO (-3262 2962);
FORCEPROP 1 LAST VALUE 0
J 0
(-3100 2950);
DISPLAY 0.489362 (-3100 2950);
PAINT SKYBLUE (-3100 2950);
FORCEPROP 2 LAST CDS_LIB pure_quanta
J 0
(-3200 2950);
DISPLAY INVISIBLE (-3200 2950);
FORCEPROP 1 LAST WATTAGE 1/16W
J 0
(-3600 2875);
DISPLAY 0.489362 (-3600 2875);
PAINT SKYBLUE (-3600 2875);
DISPLAY INVISIBLE (-3600 2875);
FORCEPROP 1 LAST MATERIAL CHIP
J 2
(-3625 2875);
DISPLAY 0.489362 (-3625 2875);
PAINT SKYBLUE (-3625 2875);
DISPLAY INVISIBLE (-3625 2875);
FORCEPROP 1 LAST TOLERANCE 5%
J 2
(-3175 2875);
DISPLAY 0.489362 (-3175 2875);
PAINT SKYBLUE (-3175 2875);
DISPLAY INVISIBLE (-3175 2875);
FORCEPROP 1 LAST PACK_TYPE 0402LF
J 2
(-3250 2875);
DISPLAY 0.489362 (-3250 2875);
PAINT SKYBLUE (-3250 2875);
DISPLAY INVISIBLE (-3250 2875);
FORCEPROP 1 LAST PATH I35
J 2
(-3150 3100);
DISPLAY 0.978723 (-3150 3100);
PAINT WHITE (-3150 3100);
DISPLAY INVISIBLE (-3150 3100);
FORCEPROP 1 LAST PART_NUMBER CS00002JB13
J 2
(-3225 3000);
DISPLAY 0.489362 (-3225 3000);
PAINT SKYBLUE (-3225 3000);
DISPLAY INVISIBLE (-3225 3000);
FORCEADD Q_RES..1
R 2
(-3200 2900);
FORCEPROP 1 LAST LOCATION R1294
J 2
(-3350 2900);
DISPLAY 0.489362 (-3350 2900);
PAINT SKYBLUE (-3350 2900);
FORCEPROP 0 LAST $SEC 1
J 0
(-3350 2950);
DISPLAY 0.680851 (-3350 2950);
PAINT MONO (-3350 2950);
DISPLAY INVISIBLE (-3350 2950);
FORCEPROP 0 LAST CDS_SEC 1
J 0
(-3350 2950);
DISPLAY 1.021277 (-3350 2950);
DISPLAY INVISIBLE (-3350 2950);
FORCEPROP 1 LASTPIN (-3100 2900) $PN 1
J 2
(-3112 2912);
DISPLAY 0.489362 (-3112 2912);
PAINT MONO (-3112 2912);
FORCEPROP 1 LASTPIN (-3300 2900) $PN 2
J 2
(-3262 2912);
DISPLAY 0.489362 (-3262 2912);
PAINT MONO (-3262 2912);
FORCEPROP 1 LAST VALUE 0
J 0
(-3100 2900);
DISPLAY 0.489362 (-3100 2900);
PAINT SKYBLUE (-3100 2900);
FORCEPROP 2 LAST CDS_LIB pure_quanta
J 0
(-3200 2900);
DISPLAY INVISIBLE (-3200 2900);
FORCEPROP 1 LAST WATTAGE 1/16W
J 0
(-3600 2825);
DISPLAY 0.489362 (-3600 2825);
PAINT SKYBLUE (-3600 2825);
DISPLAY INVISIBLE (-3600 2825);
FORCEPROP 1 LAST MATERIAL CHIP
J 2
(-3625 2825);
DISPLAY 0.489362 (-3625 2825);
PAINT SKYBLUE (-3625 2825);
DISPLAY INVISIBLE (-3625 2825);
FORCEPROP 1 LAST TOLERANCE 5%
J 2
(-3175 2825);
DISPLAY 0.489362 (-3175 2825);
PAINT SKYBLUE (-3175 2825);
DISPLAY INVISIBLE (-3175 2825);
FORCEPROP 1 LAST PACK_TYPE 0402LF
J 2
(-3250 2825);
DISPLAY 0.489362 (-3250 2825);
PAINT SKYBLUE (-3250 2825);
DISPLAY INVISIBLE (-3250 2825);
FORCEPROP 1 LAST PATH I36
J 2
(-3150 3050);
DISPLAY 0.978723 (-3150 3050);
PAINT WHITE (-3150 3050);
DISPLAY INVISIBLE (-3150 3050);
FORCEPROP 1 LAST PART_NUMBER CS00002JB13
J 2
(-3225 2950);
DISPLAY 0.489362 (-3225 2950);
PAINT SKYBLUE (-3225 2950);
DISPLAY INVISIBLE (-3225 2950);
FORCEADD Q_RES..1
R 2
(-3175 1500);
FORCEPROP 1 LAST LOCATION R1295
J 2
(-3325 1500);
DISPLAY 0.489362 (-3325 1500);
PAINT SKYBLUE (-3325 1500);
FORCEPROP 0 LAST $SEC 1
J 0
(-3325 1550);
DISPLAY 0.680851 (-3325 1550);
PAINT MONO (-3325 1550);
DISPLAY INVISIBLE (-3325 1550);
FORCEPROP 0 LAST CDS_SEC 1
J 0
(-3325 1550);
DISPLAY 1.021277 (-3325 1550);
DISPLAY INVISIBLE (-3325 1550);
FORCEPROP 1 LASTPIN (-3075 1500) $PN 1
J 2
(-3087 1512);
DISPLAY 0.489362 (-3087 1512);
PAINT MONO (-3087 1512);
FORCEPROP 1 LASTPIN (-3275 1500) $PN 2
J 2
(-3237 1512);
DISPLAY 0.489362 (-3237 1512);
PAINT MONO (-3237 1512);
FORCEPROP 1 LAST VALUE 0
J 0
(-3075 1500);
DISPLAY 0.489362 (-3075 1500);
PAINT SKYBLUE (-3075 1500);
FORCEPROP 2 LAST CDS_LIB pure_quanta
J 0
(-3175 1500);
DISPLAY INVISIBLE (-3175 1500);
FORCEPROP 1 LAST WATTAGE 1/16W
J 0
(-3575 1425);
DISPLAY 0.489362 (-3575 1425);
PAINT SKYBLUE (-3575 1425);
DISPLAY INVISIBLE (-3575 1425);
FORCEPROP 1 LAST MATERIAL CHIP
J 2
(-3600 1425);
DISPLAY 0.489362 (-3600 1425);
PAINT SKYBLUE (-3600 1425);
DISPLAY INVISIBLE (-3600 1425);
FORCEPROP 1 LAST TOLERANCE 5%
J 2
(-3150 1425);
DISPLAY 0.489362 (-3150 1425);
PAINT SKYBLUE (-3150 1425);
DISPLAY INVISIBLE (-3150 1425);
FORCEPROP 1 LAST PACK_TYPE 0402LF
J 2
(-3225 1425);
DISPLAY 0.489362 (-3225 1425);
PAINT SKYBLUE (-3225 1425);
DISPLAY INVISIBLE (-3225 1425);
FORCEPROP 1 LAST PATH I37
J 2
(-3125 1650);
DISPLAY 0.978723 (-3125 1650);
PAINT WHITE (-3125 1650);
DISPLAY INVISIBLE (-3125 1650);
FORCEPROP 1 LAST PART_NUMBER CS00002JB13
J 2
(-3200 1550);
DISPLAY 0.489362 (-3200 1550);
PAINT SKYBLUE (-3200 1550);
DISPLAY INVISIBLE (-3200 1550);
FORCEADD Q_RES..1
R 2
(-3175 1450);
FORCEPROP 1 LAST LOCATION R1296
J 2
(-3325 1450);
DISPLAY 0.489362 (-3325 1450);
PAINT SKYBLUE (-3325 1450);
FORCEPROP 0 LAST $SEC 1
J 0
(-3325 1500);
DISPLAY 0.680851 (-3325 1500);
PAINT MONO (-3325 1500);
DISPLAY INVISIBLE (-3325 1500);
FORCEPROP 0 LAST CDS_SEC 1
J 0
(-3325 1500);
DISPLAY 1.021277 (-3325 1500);
DISPLAY INVISIBLE (-3325 1500);
FORCEPROP 1 LASTPIN (-3075 1450) $PN 1
J 2
(-3087 1462);
DISPLAY 0.489362 (-3087 1462);
PAINT MONO (-3087 1462);
FORCEPROP 1 LASTPIN (-3275 1450) $PN 2
J 2
(-3237 1462);
DISPLAY 0.489362 (-3237 1462);
PAINT MONO (-3237 1462);
FORCEPROP 1 LAST VALUE 0
J 0
(-3075 1450);
DISPLAY 0.489362 (-3075 1450);
PAINT SKYBLUE (-3075 1450);
FORCEPROP 2 LAST CDS_LIB pure_quanta
J 0
(-3175 1450);
DISPLAY INVISIBLE (-3175 1450);
FORCEPROP 1 LAST WATTAGE 1/16W
J 0
(-3575 1375);
DISPLAY 0.489362 (-3575 1375);
PAINT SKYBLUE (-3575 1375);
DISPLAY INVISIBLE (-3575 1375);
FORCEPROP 1 LAST MATERIAL CHIP
J 2
(-3600 1375);
DISPLAY 0.489362 (-3600 1375);
PAINT SKYBLUE (-3600 1375);
DISPLAY INVISIBLE (-3600 1375);
FORCEPROP 1 LAST TOLERANCE 5%
J 2
(-3150 1375);
DISPLAY 0.489362 (-3150 1375);
PAINT SKYBLUE (-3150 1375);
DISPLAY INVISIBLE (-3150 1375);
FORCEPROP 1 LAST PACK_TYPE 0402LF
J 2
(-3225 1375);
DISPLAY 0.489362 (-3225 1375);
PAINT SKYBLUE (-3225 1375);
DISPLAY INVISIBLE (-3225 1375);
FORCEPROP 1 LAST PATH I38
J 2
(-3125 1600);
DISPLAY 0.978723 (-3125 1600);
PAINT WHITE (-3125 1600);
DISPLAY INVISIBLE (-3125 1600);
FORCEPROP 1 LAST PART_NUMBER CS00002JB13
J 2
(-3200 1500);
DISPLAY 0.489362 (-3200 1500);
PAINT SKYBLUE (-3200 1500);
DISPLAY INVISIBLE (-3200 1500);
FORCEADD OFFPAGE..1
(-5975 5875);
FORCEPROP 2 LAST $XR0 80 
J 0
(-6196 5875);
DISPLAY 0.638298 (-6196 5875);
PAINT MONO (-6196 5875);
FORCEPROP 2 LAST CDS_LIB standard
J 0
(-5975 5875);
DISPLAY INVISIBLE (-5975 5875);
FORCEPROP 1 LAST OFFPAGE TRUE
J 0
(-5650 5750);
DISPLAY 0.872340 (-5650 5750);
PAINT GREEN (-5650 5750);
DISPLAY INVISIBLE (-5650 5750);
FORCEPROP 1 LAST COMMENT_BODY TRUE
J 0
(-5850 5775);
DISPLAY 0.872340 (-5850 5775);
PAINT GREEN (-5850 5775);
DISPLAY INVISIBLE (-5850 5775);
FORCEPROP 2 LAST PATH I39
J 0
(-5925 5950);
DISPLAY 1.021277 (-5925 5950);
DISPLAY INVISIBLE (-5925 5950);
FORCEADD OFFPAGE..1
(-5975 5925);
FORCEPROP 2 LAST $XR1 83 
J 0
(-6286 5925);
DISPLAY 0.638298 (-6286 5925);
PAINT MONO (-6286 5925);
FORCEPROP 2 LAST $XR0 80 
J 0
(-6196 5925);
DISPLAY 0.638298 (-6196 5925);
PAINT MONO (-6196 5925);
FORCEPROP 2 LAST CDS_LIB standard
J 0
(-5975 5925);
DISPLAY INVISIBLE (-5975 5925);
FORCEPROP 1 LAST OFFPAGE TRUE
J 0
(-5650 5800);
DISPLAY 0.872340 (-5650 5800);
PAINT GREEN (-5650 5800);
DISPLAY INVISIBLE (-5650 5800);
FORCEPROP 1 LAST COMMENT_BODY TRUE
J 0
(-5850 5825);
DISPLAY 0.872340 (-5850 5825);
PAINT GREEN (-5850 5825);
DISPLAY INVISIBLE (-5850 5825);
FORCEPROP 2 LAST PATH I40
J 0
(-5925 6000);
DISPLAY 1.021277 (-5925 6000);
DISPLAY INVISIBLE (-5925 6000);
FORCEADD OFFPAGE..1
(-5950 4525);
FORCEPROP 2 LAST $XR1 83 
J 0
(-6261 4525);
DISPLAY 0.638298 (-6261 4525);
PAINT MONO (-6261 4525);
FORCEPROP 2 LAST $XR0 80 
J 0
(-6171 4525);
DISPLAY 0.638298 (-6171 4525);
PAINT MONO (-6171 4525);
FORCEPROP 2 LAST CDS_LIB standard
J 0
(-5950 4525);
DISPLAY INVISIBLE (-5950 4525);
FORCEPROP 1 LAST OFFPAGE TRUE
J 0
(-5625 4400);
DISPLAY 0.872340 (-5625 4400);
PAINT GREEN (-5625 4400);
DISPLAY INVISIBLE (-5625 4400);
FORCEPROP 1 LAST COMMENT_BODY TRUE
J 0
(-5825 4425);
DISPLAY 0.872340 (-5825 4425);
PAINT GREEN (-5825 4425);
DISPLAY INVISIBLE (-5825 4425);
FORCEPROP 2 LAST PATH I41
J 0
(-5900 4600);
DISPLAY 1.021277 (-5900 4600);
DISPLAY INVISIBLE (-5900 4600);
FORCEADD OFFPAGE..1
(-5950 4475);
FORCEPROP 2 LAST $XR0 80 
J 0
(-6171 4475);
DISPLAY 0.638298 (-6171 4475);
PAINT MONO (-6171 4475);
FORCEPROP 2 LAST CDS_LIB standard
J 0
(-5950 4475);
DISPLAY INVISIBLE (-5950 4475);
FORCEPROP 1 LAST OFFPAGE TRUE
J 0
(-5625 4350);
DISPLAY 0.872340 (-5625 4350);
PAINT GREEN (-5625 4350);
DISPLAY INVISIBLE (-5625 4350);
FORCEPROP 1 LAST COMMENT_BODY TRUE
J 0
(-5825 4375);
DISPLAY 0.872340 (-5825 4375);
PAINT GREEN (-5825 4375);
DISPLAY INVISIBLE (-5825 4375);
FORCEPROP 2 LAST PATH I42
J 0
(-5900 4550);
DISPLAY 1.021277 (-5900 4550);
DISPLAY INVISIBLE (-5900 4550);
FORCEADD OFFPAGE..1
(-5950 2950);
FORCEPROP 2 LAST $XR0 80 
J 0
(-6171 2950);
DISPLAY 0.638298 (-6171 2950);
PAINT MONO (-6171 2950);
FORCEPROP 2 LAST CDS_LIB standard
J 0
(-5950 2950);
DISPLAY INVISIBLE (-5950 2950);
FORCEPROP 1 LAST OFFPAGE TRUE
J 0
(-5625 2825);
DISPLAY 0.872340 (-5625 2825);
PAINT GREEN (-5625 2825);
DISPLAY INVISIBLE (-5625 2825);
FORCEPROP 1 LAST COMMENT_BODY TRUE
J 0
(-5825 2850);
DISPLAY 0.872340 (-5825 2850);
PAINT GREEN (-5825 2850);
DISPLAY INVISIBLE (-5825 2850);
FORCEPROP 2 LAST PATH I43
J 0
(-5900 3025);
DISPLAY 1.021277 (-5900 3025);
DISPLAY INVISIBLE (-5900 3025);
FORCEADD OFFPAGE..1
(-5950 3000);
FORCEPROP 2 LAST $XR1 83 
J 0
(-6261 3000);
DISPLAY 0.638298 (-6261 3000);
PAINT MONO (-6261 3000);
FORCEPROP 2 LAST $XR0 80 
J 0
(-6171 3000);
DISPLAY 0.638298 (-6171 3000);
PAINT MONO (-6171 3000);
FORCEPROP 2 LAST CDS_LIB standard
J 0
(-5950 3000);
DISPLAY INVISIBLE (-5950 3000);
FORCEPROP 1 LAST OFFPAGE TRUE
J 0
(-5625 2875);
DISPLAY 0.872340 (-5625 2875);
PAINT GREEN (-5625 2875);
DISPLAY INVISIBLE (-5625 2875);
FORCEPROP 1 LAST COMMENT_BODY TRUE
J 0
(-5825 2900);
DISPLAY 0.872340 (-5825 2900);
PAINT GREEN (-5825 2900);
DISPLAY INVISIBLE (-5825 2900);
FORCEPROP 2 LAST PATH I44
J 0
(-5900 3075);
DISPLAY 1.021277 (-5900 3075);
DISPLAY INVISIBLE (-5900 3075);
FORCEADD OFFPAGE..1
(-5900 1550);
FORCEPROP 2 LAST $XR1 83 
J 0
(-6241 1550);
DISPLAY 0.638298 (-6241 1550);
PAINT MONO (-6241 1550);
FORCEPROP 2 LAST $XR0 80 
J 0
(-6151 1550);
DISPLAY 0.638298 (-6151 1550);
PAINT MONO (-6151 1550);
FORCEPROP 2 LAST CDS_LIB standard
J 0
(-5900 1550);
DISPLAY INVISIBLE (-5900 1550);
FORCEPROP 1 LAST OFFPAGE TRUE
J 0
(-5575 1425);
DISPLAY 0.872340 (-5575 1425);
PAINT GREEN (-5575 1425);
DISPLAY INVISIBLE (-5575 1425);
FORCEPROP 1 LAST COMMENT_BODY TRUE
J 0
(-5775 1450);
DISPLAY 0.872340 (-5775 1450);
PAINT GREEN (-5775 1450);
DISPLAY INVISIBLE (-5775 1450);
FORCEPROP 2 LAST PATH I45
J 0
(-5850 1625);
DISPLAY 1.021277 (-5850 1625);
DISPLAY INVISIBLE (-5850 1625);
FORCEADD OFFPAGE..1
(-5900 1500);
FORCEPROP 2 LAST $XR0 80 
J 0
(-6151 1500);
DISPLAY 0.638298 (-6151 1500);
PAINT MONO (-6151 1500);
FORCEPROP 2 LAST CDS_LIB standard
J 0
(-5900 1500);
DISPLAY INVISIBLE (-5900 1500);
FORCEPROP 1 LAST OFFPAGE TRUE
J 0
(-5575 1375);
DISPLAY 0.872340 (-5575 1375);
PAINT GREEN (-5575 1375);
DISPLAY INVISIBLE (-5575 1375);
FORCEPROP 1 LAST COMMENT_BODY TRUE
J 0
(-5775 1400);
DISPLAY 0.872340 (-5775 1400);
PAINT GREEN (-5775 1400);
DISPLAY INVISIBLE (-5775 1400);
FORCEPROP 2 LAST PATH I46
J 0
(-5850 1575);
DISPLAY 1.021277 (-5850 1575);
DISPLAY INVISIBLE (-5850 1575);
FORCEADD PI3CSW12ZUAEX..1
(-4775 5775);
FORCEPROP 1 LAST LOCATION U105
J 0
(-4919 6268);
DISPLAY 0.489362 (-4919 6268);
PAINT SKYBLUE (-4919 6268);
FORCEPROP 0 LAST $SEC 1
J 0
(-4900 6425);
DISPLAY 0.680851 (-4900 6425);
PAINT MONO (-4900 6425);
DISPLAY INVISIBLE (-4900 6425);
FORCEPROP 0 LAST CDS_SEC 1
J 0
(-4900 6425);
DISPLAY 1.021277 (-4900 6425);
DISPLAY INVISIBLE (-4900 6425);
FORCEPROP 0 LASTPIN (-5075 5775) $PN 1
J 2
(-5085 5785);
DISPLAY 0.489362 (-5085 5785);
PAINT MONO (-5085 5785);
FORCEPROP 0 LASTPIN (-5075 5725) $PN 2
J 2
(-5085 5735);
DISPLAY 0.489362 (-5085 5735);
PAINT MONO (-5085 5735);
FORCEPROP 0 LASTPIN (-5075 5675) $PN 3
J 2
(-5085 5685);
DISPLAY 0.489362 (-5085 5685);
PAINT MONO (-5085 5685);
FORCEPROP 0 LASTPIN (-5075 5625) $PN 4
J 2
(-5085 5635);
DISPLAY 0.489362 (-5085 5635);
PAINT MONO (-5085 5635);
FORCEPROP 0 LASTPIN (-4475 5875) $PN 8
J 0
(-4465 5885);
DISPLAY 0.489362 (-4465 5885);
PAINT MONO (-4465 5885);
FORCEPROP 0 LASTPIN (-4475 5825) $PN 7
J 0
(-4465 5835);
DISPLAY 0.489362 (-4465 5835);
PAINT MONO (-4465 5835);
FORCEPROP 0 LASTPIN (-4475 5625) $PN 5
J 0
(-4465 5635);
DISPLAY 0.489362 (-4465 5635);
PAINT MONO (-4465 5635);
FORCEPROP 0 LASTPIN (-5075 5925) $PN 6
J 2
(-5085 5935);
DISPLAY 0.489362 (-5085 5935);
PAINT MONO (-5085 5935);
FORCEPROP 0 LASTPIN (-5075 5875) $PN 9
J 2
(-5085 5885);
DISPLAY 0.489362 (-5085 5885);
PAINT MONO (-5085 5885);
FORCEPROP 0 LASTPIN (-4475 5925) $PN 10
J 0
(-4465 5935);
DISPLAY 0.489362 (-4465 5935);
PAINT MONO (-4465 5935);
FORCEPROP 2 LAST VALUE PI3CSW12ZUAEX
J 0
(-4900 6325);
DISPLAY 0.489362 (-4900 6325);
PAINT SKYBLUE (-4900 6325);
FORCEPROP 2 LAST PART_TYPE SMLF
J 0
(-4900 6375);
DISPLAY 1.021277 (-4900 6375);
FORCEPROP 1 LAST MATERIAL IC
J 0
(-4919 5994);
DISPLAY 0.489362 (-4919 5994);
PAINT SKYBLUE (-4919 5994);
FORCEPROP 1 LAST NEEDS_NO_SIZE TRUE
J 0
(-4775 5775);
DISPLAY 0.723404 (-4775 5775);
PAINT GREEN (-4775 5775);
DISPLAY INVISIBLE (-4775 5775);
FORCEPROP 1 LAST CDS_LMAN_SYM_OUTLINE -150,200,150,-200
J 0
(-4775 5775);
DISPLAY 0.468085 (-4775 5775);
PAINT GREEN (-4775 5775);
DISPLAY INVISIBLE (-4775 5775);
FORCEPROP 2 LAST CDS_LIB pure_quanta
J 0
(-4775 5775);
DISPLAY INVISIBLE (-4775 5775);
FORCEPROP 1 LAST PATH I47
J 0
(-4775 5775);
DISPLAY 0.723404 (-4775 5775);
PAINT GREEN (-4775 5775);
DISPLAY INVISIBLE (-4775 5775);
FORCEPROP 1 LAST PART_NUMBER AL3CSW12000
J 0
(-4919 6121);
DISPLAY 0.489362 (-4919 6121);
PAINT SKYBLUE (-4919 6121);
DISPLAY INVISIBLE (-4919 6121);
FORCEADD UNIVERSAL_GND..1
(-4325 5450);
FORCEPROP 3 LASTPIN (-4325 5500) SIG_NAME GND\g
J 0
(-4315 5510);
DISPLAY 0.659574 (-4315 5510);
PAINT MONO (-4315 5510);
DISPLAY INVISIBLE (-4315 5510);
FORCEPROP 2 LAST CDS_LIB pure_quanta_power
J 0
(-4325 5450);
DISPLAY INVISIBLE (-4325 5450);
FORCEPROP 1 LAST HDL_POWER GND
J 1
(-4300 5375);
DISPLAY 0.872340 (-4300 5375);
PAINT GREEN (-4300 5375);
DISPLAY INVISIBLE (-4300 5375);
FORCEPROP 1 LAST PATH I48
J 0
(-4250 5450);
DISPLAY 0.872340 (-4250 5450);
PAINT AQUA (-4250 5450);
DISPLAY INVISIBLE (-4250 5450);
FORCEADD UNIVERSAL_GND..1
(-4275 6000);
FORCEPROP 3 LASTPIN (-4275 6050) SIG_NAME GND\g
J 0
(-4265 6060);
DISPLAY 0.659574 (-4265 6060);
PAINT MONO (-4265 6060);
DISPLAY INVISIBLE (-4265 6060);
FORCEPROP 2 LAST CDS_LIB pure_quanta_power
J 2
(-4275 6000);
DISPLAY INVISIBLE (-4275 6000);
FORCEPROP 1 LAST HDL_POWER GND
J 1
(-4250 5925);
DISPLAY 0.872340 (-4250 5925);
PAINT GREEN (-4250 5925);
DISPLAY INVISIBLE (-4250 5925);
FORCEPROP 1 LAST PATH I49
J 0
(-4200 6000);
DISPLAY 0.872340 (-4200 6000);
PAINT AQUA (-4200 6000);
DISPLAY INVISIBLE (-4200 6000);
FORCEADD Q_CAP..1
(-4275 6200);
FORCEPROP 1 LAST LOCATION C1336
J 0
(-4225 6350);
DISPLAY 0.489362 (-4225 6350);
PAINT SKYBLUE (-4225 6350);
FORCEPROP 0 LAST $SEC 1
J 2
(-4225 6375);
DISPLAY 0.680851 (-4225 6375);
PAINT MONO (-4225 6375);
DISPLAY INVISIBLE (-4225 6375);
FORCEPROP 0 LAST CDS_SEC 1
J 2
(-4225 6375);
DISPLAY 1.021277 (-4225 6375);
DISPLAY INVISIBLE (-4225 6375);
FORCEPROP 1 LASTPIN (-4275 6300) $PN 1
J 0
(-4265 6280);
DISPLAY 0.489362 (-4265 6280);
PAINT MONO (-4265 6280);
FORCEPROP 1 LASTPIN (-4275 6100) $PN 2
J 0
(-4265 6080);
DISPLAY 0.489362 (-4265 6080);
PAINT MONO (-4265 6080);
FORCEPROP 1 LAST VOLTAGE 25V
J 0
(-4225 6250);
DISPLAY 0.489362 (-4225 6250);
PAINT SKYBLUE (-4225 6250);
FORCEPROP 1 LAST VALUE 0.1UF
J 0
(-4225 6300);
DISPLAY 0.489362 (-4225 6300);
PAINT SKYBLUE (-4225 6300);
FORCEPROP 1 LAST TOLERANCE 10%
J 0
(-4225 6200);
DISPLAY 0.489362 (-4225 6200);
PAINT SKYBLUE (-4225 6200);
FORCEPROP 1 LAST MATERIAL X7R
J 0
(-4225 6150);
DISPLAY 0.489362 (-4225 6150);
PAINT SKYBLUE (-4225 6150);
FORCEPROP 1 LAST PACK_TYPE 0402
J 0
(-4225 6100);
DISPLAY 0.489362 (-4225 6100);
PAINT SKYBLUE (-4225 6100);
FORCEPROP 2 LAST CDS_LIB pure_quanta
J 2
(-4275 6200);
DISPLAY INVISIBLE (-4275 6200);
FORCEPROP 1 LAST PATH I50
J 0
(-4225 6350);
DISPLAY 0.978723 (-4225 6350);
PAINT WHITE (-4225 6350);
DISPLAY INVISIBLE (-4225 6350);
FORCEPROP 1 LAST PART_NUMBER CH4104K1B00
J 0
(-4225 6050);
DISPLAY 0.489362 (-4225 6050);
PAINT SKYBLUE (-4225 6050);
DISPLAY INVISIBLE (-4225 6050);
FORCEADD UNIVERSAL_POWER..1
R 2
(-4350 6475);
FORCEPROP 3 LASTPIN (-4350 6425) SIG_NAME P3V3_AUX\g
J 0
(-4340 6435);
DISPLAY 0.659574 (-4340 6435);
PAINT MONO (-4340 6435);
DISPLAY INVISIBLE (-4340 6435);
FORCEPROP 1 LAST HDL_POWER P3V3_AUX
J 1
(-4350 6525);
DISPLAY 0.489362 (-4350 6525);
PAINT GREEN (-4350 6525);
FORCEPROP 2 LAST CDS_LIB pure_quanta_power
J 2
(-4350 6475);
DISPLAY INVISIBLE (-4350 6475);
FORCEPROP 1 LAST PATH I51
J 2
(-4400 6500);
DISPLAY 0.872340 (-4400 6500);
PAINT AQUA (-4400 6500);
DISPLAY INVISIBLE (-4400 6500);
FORCEADD OFFPAGE..3
(-1825 5825);
FORCEPROP 2 LAST $XR5 91 
J 0
(-1161 5825);
DISPLAY 0.638298 (-1161 5825);
PAINT MONO (-1161 5825);
FORCEPROP 2 LAST $XR4 90 
J 0
(-1251 5825);
DISPLAY 0.638298 (-1251 5825);
PAINT MONO (-1251 5825);
FORCEPROP 2 LAST $XR3 89 
J 0
(-1341 5825);
DISPLAY 0.638298 (-1341 5825);
PAINT MONO (-1341 5825);
FORCEPROP 2 LAST $XR2 88 
J 0
(-1431 5825);
DISPLAY 0.638298 (-1431 5825);
PAINT MONO (-1431 5825);
FORCEPROP 2 LAST $XR1 87 
J 0
(-1521 5825);
DISPLAY 0.638298 (-1521 5825);
PAINT MONO (-1521 5825);
FORCEPROP 2 LAST $XR0 86 
J 0
(-1611 5825);
DISPLAY 0.638298 (-1611 5825);
PAINT MONO (-1611 5825);
FORCEPROP 2 LAST CDS_LIB standard
J 0
(-1825 5825);
DISPLAY INVISIBLE (-1825 5825);
FORCEPROP 1 LAST OFFPAGE TRUE
J 0
(-1500 5700);
DISPLAY 0.872340 (-1500 5700);
PAINT GREEN (-1500 5700);
DISPLAY INVISIBLE (-1500 5700);
FORCEPROP 1 LAST COMMENT_BODY TRUE
J 0
(-1875 5725);
DISPLAY 0.872340 (-1875 5725);
PAINT GREEN (-1875 5725);
DISPLAY INVISIBLE (-1875 5725);
FORCEPROP 2 LAST PATH I52
J 0
(-1600 5875);
DISPLAY 1.021277 (-1600 5875);
DISPLAY INVISIBLE (-1600 5875);
FORCEADD OFFPAGE..2
(-1825 5875);
FORCEPROP 2 LAST $XR5 91 
J 0
(-1186 5875);
DISPLAY 0.638298 (-1186 5875);
PAINT MONO (-1186 5875);
FORCEPROP 2 LAST $XR4 90 
J 0
(-1276 5875);
DISPLAY 0.638298 (-1276 5875);
PAINT MONO (-1276 5875);
FORCEPROP 2 LAST $XR3 89 
J 0
(-1366 5875);
DISPLAY 0.638298 (-1366 5875);
PAINT MONO (-1366 5875);
FORCEPROP 2 LAST $XR2 88 
J 0
(-1456 5875);
DISPLAY 0.638298 (-1456 5875);
PAINT MONO (-1456 5875);
FORCEPROP 2 LAST $XR1 87 
J 0
(-1546 5875);
DISPLAY 0.638298 (-1546 5875);
PAINT MONO (-1546 5875);
FORCEPROP 2 LAST $XR0 86 
J 0
(-1636 5875);
DISPLAY 0.638298 (-1636 5875);
PAINT MONO (-1636 5875);
FORCEPROP 2 LAST CDS_LIB standard
J 0
(-1825 5875);
DISPLAY INVISIBLE (-1825 5875);
FORCEPROP 1 LAST OFFPAGE TRUE
J 0
(-1500 5750);
DISPLAY 0.872340 (-1500 5750);
PAINT GREEN (-1500 5750);
DISPLAY INVISIBLE (-1500 5750);
FORCEPROP 1 LAST COMMENT_BODY TRUE
J 0
(-1870 5780);
DISPLAY 0.872340 (-1870 5780);
PAINT GREEN (-1870 5780);
DISPLAY INVISIBLE (-1870 5780);
FORCEPROP 2 LAST PATH I53
J 0
(-1625 5925);
DISPLAY 1.021277 (-1625 5925);
DISPLAY INVISIBLE (-1625 5925);
FORCEADD PI3CSW12ZUAEX..1
(-4750 4375);
FORCEPROP 1 LAST LOCATION U106
J 0
(-4894 4868);
DISPLAY 0.489362 (-4894 4868);
PAINT SKYBLUE (-4894 4868);
FORCEPROP 0 LAST $SEC 1
J 0
(-4875 5025);
DISPLAY 0.680851 (-4875 5025);
PAINT MONO (-4875 5025);
DISPLAY INVISIBLE (-4875 5025);
FORCEPROP 0 LAST CDS_SEC 1
J 0
(-4875 5025);
DISPLAY 1.021277 (-4875 5025);
DISPLAY INVISIBLE (-4875 5025);
FORCEPROP 0 LASTPIN (-5050 4375) $PN 1
J 2
(-5060 4385);
DISPLAY 0.489362 (-5060 4385);
PAINT MONO (-5060 4385);
FORCEPROP 0 LASTPIN (-5050 4325) $PN 2
J 2
(-5060 4335);
DISPLAY 0.489362 (-5060 4335);
PAINT MONO (-5060 4335);
FORCEPROP 0 LASTPIN (-5050 4275) $PN 3
J 2
(-5060 4285);
DISPLAY 0.489362 (-5060 4285);
PAINT MONO (-5060 4285);
FORCEPROP 0 LASTPIN (-5050 4225) $PN 4
J 2
(-5060 4235);
DISPLAY 0.489362 (-5060 4235);
PAINT MONO (-5060 4235);
FORCEPROP 0 LASTPIN (-4450 4475) $PN 8
J 0
(-4440 4485);
DISPLAY 0.489362 (-4440 4485);
PAINT MONO (-4440 4485);
FORCEPROP 0 LASTPIN (-4450 4425) $PN 7
J 0
(-4440 4435);
DISPLAY 0.489362 (-4440 4435);
PAINT MONO (-4440 4435);
FORCEPROP 0 LASTPIN (-4450 4225) $PN 5
J 0
(-4440 4235);
DISPLAY 0.489362 (-4440 4235);
PAINT MONO (-4440 4235);
FORCEPROP 0 LASTPIN (-5050 4525) $PN 6
J 2
(-5060 4535);
DISPLAY 0.489362 (-5060 4535);
PAINT MONO (-5060 4535);
FORCEPROP 0 LASTPIN (-5050 4475) $PN 9
J 2
(-5060 4485);
DISPLAY 0.489362 (-5060 4485);
PAINT MONO (-5060 4485);
FORCEPROP 0 LASTPIN (-4450 4525) $PN 10
J 0
(-4440 4535);
DISPLAY 0.489362 (-4440 4535);
PAINT MONO (-4440 4535);
FORCEPROP 2 LAST PART_TYPE SMLF
J 0
(-4875 4975);
DISPLAY 1.021277 (-4875 4975);
FORCEPROP 2 LAST VALUE PI3CSW12ZUAEX
J 0
(-4875 4925);
DISPLAY 0.489362 (-4875 4925);
PAINT SKYBLUE (-4875 4925);
FORCEPROP 1 LAST MATERIAL IC
J 0
(-4894 4594);
DISPLAY 0.489362 (-4894 4594);
PAINT SKYBLUE (-4894 4594);
FORCEPROP 1 LAST NEEDS_NO_SIZE TRUE
J 0
(-4750 4375);
DISPLAY 0.723404 (-4750 4375);
PAINT GREEN (-4750 4375);
DISPLAY INVISIBLE (-4750 4375);
FORCEPROP 1 LAST CDS_LMAN_SYM_OUTLINE -150,200,150,-200
J 0
(-4750 4375);
DISPLAY 0.468085 (-4750 4375);
PAINT GREEN (-4750 4375);
DISPLAY INVISIBLE (-4750 4375);
FORCEPROP 2 LAST CDS_LIB pure_quanta
J 0
(-4750 4375);
DISPLAY INVISIBLE (-4750 4375);
FORCEPROP 1 LAST PATH I54
J 0
(-4750 4375);
DISPLAY 0.723404 (-4750 4375);
PAINT GREEN (-4750 4375);
DISPLAY INVISIBLE (-4750 4375);
FORCEPROP 1 LAST PART_NUMBER AL3CSW12000
J 0
(-4894 4721);
DISPLAY 0.489362 (-4894 4721);
PAINT SKYBLUE (-4894 4721);
DISPLAY INVISIBLE (-4894 4721);
FORCEADD UNIVERSAL_POWER..1
R 2
(-4325 5075);
FORCEPROP 3 LASTPIN (-4325 5025) SIG_NAME P3V3_AUX\g
J 0
(-4315 5035);
DISPLAY 0.659574 (-4315 5035);
PAINT MONO (-4315 5035);
DISPLAY INVISIBLE (-4315 5035);
FORCEPROP 1 LAST HDL_POWER P3V3_AUX
J 1
(-4325 5125);
DISPLAY 0.489362 (-4325 5125);
PAINT GREEN (-4325 5125);
FORCEPROP 2 LAST CDS_LIB pure_quanta_power
J 2
(-4325 5075);
DISPLAY INVISIBLE (-4325 5075);
FORCEPROP 1 LAST PATH I55
J 2
(-4375 5100);
DISPLAY 0.872340 (-4375 5100);
PAINT AQUA (-4375 5100);
DISPLAY INVISIBLE (-4375 5100);
FORCEADD Q_CAP..1
(-4250 4800);
FORCEPROP 1 LAST LOCATION C1337
J 0
(-4200 4950);
DISPLAY 0.489362 (-4200 4950);
PAINT SKYBLUE (-4200 4950);
FORCEPROP 0 LAST $SEC 1
J 2
(-4200 4975);
DISPLAY 0.680851 (-4200 4975);
PAINT MONO (-4200 4975);
DISPLAY INVISIBLE (-4200 4975);
FORCEPROP 0 LAST CDS_SEC 1
J 2
(-4200 4975);
DISPLAY 1.021277 (-4200 4975);
DISPLAY INVISIBLE (-4200 4975);
FORCEPROP 1 LASTPIN (-4250 4900) $PN 1
J 0
(-4240 4880);
DISPLAY 0.489362 (-4240 4880);
PAINT MONO (-4240 4880);
FORCEPROP 1 LASTPIN (-4250 4700) $PN 2
J 0
(-4240 4680);
DISPLAY 0.489362 (-4240 4680);
PAINT MONO (-4240 4680);
FORCEPROP 1 LAST MATERIAL X7R
J 0
(-4200 4750);
DISPLAY 0.489362 (-4200 4750);
PAINT SKYBLUE (-4200 4750);
FORCEPROP 1 LAST TOLERANCE 10%
J 0
(-4200 4800);
DISPLAY 0.489362 (-4200 4800);
PAINT SKYBLUE (-4200 4800);
FORCEPROP 1 LAST PACK_TYPE 0402
J 0
(-4200 4700);
DISPLAY 0.489362 (-4200 4700);
PAINT SKYBLUE (-4200 4700);
FORCEPROP 1 LAST VOLTAGE 25V
J 0
(-4200 4850);
DISPLAY 0.489362 (-4200 4850);
PAINT SKYBLUE (-4200 4850);
FORCEPROP 1 LAST VALUE 0.1UF
J 0
(-4200 4900);
DISPLAY 0.489362 (-4200 4900);
PAINT SKYBLUE (-4200 4900);
FORCEPROP 2 LAST CDS_LIB pure_quanta
J 2
(-4250 4800);
DISPLAY INVISIBLE (-4250 4800);
FORCEPROP 1 LAST PATH I56
J 0
(-4200 4950);
DISPLAY 0.978723 (-4200 4950);
PAINT WHITE (-4200 4950);
DISPLAY INVISIBLE (-4200 4950);
FORCEPROP 1 LAST PART_NUMBER CH4104K1B00
J 0
(-4200 4650);
DISPLAY 0.489362 (-4200 4650);
PAINT SKYBLUE (-4200 4650);
DISPLAY INVISIBLE (-4200 4650);
FORCEADD UNIVERSAL_GND..1
(-4250 4600);
FORCEPROP 3 LASTPIN (-4250 4650) SIG_NAME GND\g
J 0
(-4240 4660);
DISPLAY 0.659574 (-4240 4660);
PAINT MONO (-4240 4660);
DISPLAY INVISIBLE (-4240 4660);
FORCEPROP 2 LAST CDS_LIB pure_quanta_power
J 2
(-4250 4600);
DISPLAY INVISIBLE (-4250 4600);
FORCEPROP 1 LAST HDL_POWER GND
J 1
(-4225 4525);
DISPLAY 0.872340 (-4225 4525);
PAINT GREEN (-4225 4525);
DISPLAY INVISIBLE (-4225 4525);
FORCEPROP 1 LAST PATH I57
J 0
(-4175 4600);
DISPLAY 0.872340 (-4175 4600);
PAINT AQUA (-4175 4600);
DISPLAY INVISIBLE (-4175 4600);
FORCEADD UNIVERSAL_GND..1
(-4300 4050);
FORCEPROP 3 LASTPIN (-4300 4100) SIG_NAME GND\g
J 0
(-4290 4110);
DISPLAY 0.659574 (-4290 4110);
PAINT MONO (-4290 4110);
DISPLAY INVISIBLE (-4290 4110);
FORCEPROP 2 LAST CDS_LIB pure_quanta_power
J 0
(-4300 4050);
DISPLAY INVISIBLE (-4300 4050);
FORCEPROP 1 LAST HDL_POWER GND
J 1
(-4275 3975);
DISPLAY 0.872340 (-4275 3975);
PAINT GREEN (-4275 3975);
DISPLAY INVISIBLE (-4275 3975);
FORCEPROP 1 LAST PATH I58
J 0
(-4225 4050);
DISPLAY 0.872340 (-4225 4050);
PAINT AQUA (-4225 4050);
DISPLAY INVISIBLE (-4225 4050);
FORCEADD UNIVERSAL_GND..1
(-4300 2525);
FORCEPROP 3 LASTPIN (-4300 2575) SIG_NAME GND\g
J 0
(-4290 2585);
DISPLAY 0.659574 (-4290 2585);
PAINT MONO (-4290 2585);
DISPLAY INVISIBLE (-4290 2585);
FORCEPROP 2 LAST CDS_LIB pure_quanta_power
J 0
(-4300 2525);
DISPLAY INVISIBLE (-4300 2525);
FORCEPROP 1 LAST HDL_POWER GND
J 1
(-4275 2450);
DISPLAY 0.872340 (-4275 2450);
PAINT GREEN (-4275 2450);
DISPLAY INVISIBLE (-4275 2450);
FORCEPROP 1 LAST PATH I59
J 0
(-4225 2525);
DISPLAY 0.872340 (-4225 2525);
PAINT AQUA (-4225 2525);
DISPLAY INVISIBLE (-4225 2525);
FORCEADD UNIVERSAL_GND..1
(-4250 3075);
FORCEPROP 3 LASTPIN (-4250 3125) SIG_NAME GND\g
J 0
(-4240 3135);
DISPLAY 0.659574 (-4240 3135);
PAINT MONO (-4240 3135);
DISPLAY INVISIBLE (-4240 3135);
FORCEPROP 2 LAST CDS_LIB pure_quanta_power
J 2
(-4250 3075);
DISPLAY INVISIBLE (-4250 3075);
FORCEPROP 1 LAST HDL_POWER GND
J 1
(-4225 3000);
DISPLAY 0.872340 (-4225 3000);
PAINT GREEN (-4225 3000);
DISPLAY INVISIBLE (-4225 3000);
FORCEPROP 1 LAST PATH I60
J 0
(-4175 3075);
DISPLAY 0.872340 (-4175 3075);
PAINT AQUA (-4175 3075);
DISPLAY INVISIBLE (-4175 3075);
FORCEADD Q_CAP..1
(-4250 3275);
FORCEPROP 1 LAST LOCATION C1338
J 0
(-4200 3425);
DISPLAY 0.489362 (-4200 3425);
PAINT SKYBLUE (-4200 3425);
FORCEPROP 0 LAST $SEC 1
J 2
(-4200 3450);
DISPLAY 0.680851 (-4200 3450);
PAINT MONO (-4200 3450);
DISPLAY INVISIBLE (-4200 3450);
FORCEPROP 0 LAST CDS_SEC 1
J 2
(-4200 3450);
DISPLAY 1.021277 (-4200 3450);
DISPLAY INVISIBLE (-4200 3450);
FORCEPROP 1 LASTPIN (-4250 3375) $PN 1
J 0
(-4240 3355);
DISPLAY 0.489362 (-4240 3355);
PAINT MONO (-4240 3355);
FORCEPROP 1 LASTPIN (-4250 3175) $PN 2
J 0
(-4240 3155);
DISPLAY 0.489362 (-4240 3155);
PAINT MONO (-4240 3155);
FORCEPROP 1 LAST MATERIAL X7R
J 0
(-4200 3225);
DISPLAY 0.489362 (-4200 3225);
PAINT SKYBLUE (-4200 3225);
FORCEPROP 1 LAST PACK_TYPE 0402
J 0
(-4200 3175);
DISPLAY 0.489362 (-4200 3175);
PAINT SKYBLUE (-4200 3175);
FORCEPROP 1 LAST VOLTAGE 25V
J 0
(-4200 3325);
DISPLAY 0.489362 (-4200 3325);
PAINT SKYBLUE (-4200 3325);
FORCEPROP 1 LAST TOLERANCE 10%
J 0
(-4200 3275);
DISPLAY 0.489362 (-4200 3275);
PAINT SKYBLUE (-4200 3275);
FORCEPROP 1 LAST VALUE 0.1UF
J 0
(-4200 3375);
DISPLAY 0.489362 (-4200 3375);
PAINT SKYBLUE (-4200 3375);
FORCEPROP 2 LAST CDS_LIB pure_quanta
J 2
(-4250 3275);
DISPLAY INVISIBLE (-4250 3275);
FORCEPROP 1 LAST PATH I61
J 0
(-4200 3425);
DISPLAY 0.978723 (-4200 3425);
PAINT WHITE (-4200 3425);
DISPLAY INVISIBLE (-4200 3425);
FORCEPROP 1 LAST PART_NUMBER CH4104K1B00
J 0
(-4200 3125);
DISPLAY 0.489362 (-4200 3125);
PAINT SKYBLUE (-4200 3125);
DISPLAY INVISIBLE (-4200 3125);
FORCEADD UNIVERSAL_POWER..1
R 2
(-4325 3550);
FORCEPROP 3 LASTPIN (-4325 3500) SIG_NAME P3V3_AUX\g
J 0
(-4315 3510);
DISPLAY 0.659574 (-4315 3510);
PAINT MONO (-4315 3510);
DISPLAY INVISIBLE (-4315 3510);
FORCEPROP 1 LAST HDL_POWER P3V3_AUX
J 1
(-4325 3600);
DISPLAY 0.489362 (-4325 3600);
PAINT GREEN (-4325 3600);
FORCEPROP 2 LAST CDS_LIB pure_quanta_power
J 2
(-4325 3550);
DISPLAY INVISIBLE (-4325 3550);
FORCEPROP 1 LAST PATH I62
J 2
(-4375 3575);
DISPLAY 0.872340 (-4375 3575);
PAINT AQUA (-4375 3575);
DISPLAY INVISIBLE (-4375 3575);
FORCEADD PI3CSW12ZUAEX..1
(-4750 2850);
FORCEPROP 1 LAST LOCATION U107
J 0
(-4894 3343);
DISPLAY 0.489362 (-4894 3343);
PAINT SKYBLUE (-4894 3343);
FORCEPROP 0 LAST $SEC 1
J 0
(-4875 3500);
DISPLAY 0.680851 (-4875 3500);
PAINT MONO (-4875 3500);
DISPLAY INVISIBLE (-4875 3500);
FORCEPROP 0 LAST CDS_SEC 1
J 0
(-4875 3500);
DISPLAY 1.021277 (-4875 3500);
DISPLAY INVISIBLE (-4875 3500);
FORCEPROP 0 LASTPIN (-5050 2850) $PN 1
J 2
(-5060 2860);
DISPLAY 0.489362 (-5060 2860);
PAINT MONO (-5060 2860);
FORCEPROP 0 LASTPIN (-5050 2800) $PN 2
J 2
(-5060 2810);
DISPLAY 0.489362 (-5060 2810);
PAINT MONO (-5060 2810);
FORCEPROP 0 LASTPIN (-5050 2750) $PN 3
J 2
(-5060 2760);
DISPLAY 0.489362 (-5060 2760);
PAINT MONO (-5060 2760);
FORCEPROP 0 LASTPIN (-5050 2700) $PN 4
J 2
(-5060 2710);
DISPLAY 0.489362 (-5060 2710);
PAINT MONO (-5060 2710);
FORCEPROP 0 LASTPIN (-4450 2950) $PN 8
J 0
(-4440 2960);
DISPLAY 0.489362 (-4440 2960);
PAINT MONO (-4440 2960);
FORCEPROP 0 LASTPIN (-4450 2900) $PN 7
J 0
(-4440 2910);
DISPLAY 0.489362 (-4440 2910);
PAINT MONO (-4440 2910);
FORCEPROP 0 LASTPIN (-4450 2700) $PN 5
J 0
(-4440 2710);
DISPLAY 0.489362 (-4440 2710);
PAINT MONO (-4440 2710);
FORCEPROP 0 LASTPIN (-5050 3000) $PN 6
J 2
(-5060 3010);
DISPLAY 0.489362 (-5060 3010);
PAINT MONO (-5060 3010);
FORCEPROP 0 LASTPIN (-5050 2950) $PN 9
J 2
(-5060 2960);
DISPLAY 0.489362 (-5060 2960);
PAINT MONO (-5060 2960);
FORCEPROP 0 LASTPIN (-4450 3000) $PN 10
J 0
(-4440 3010);
DISPLAY 0.489362 (-4440 3010);
PAINT MONO (-4440 3010);
FORCEPROP 2 LAST PART_TYPE SMLF
J 0
(-4875 3450);
DISPLAY 1.021277 (-4875 3450);
FORCEPROP 1 LAST MATERIAL IC
J 0
(-4894 3069);
DISPLAY 0.489362 (-4894 3069);
PAINT SKYBLUE (-4894 3069);
FORCEPROP 2 LAST VALUE PI3CSW12ZUAEX
J 0
(-4875 3400);
DISPLAY 0.489362 (-4875 3400);
PAINT SKYBLUE (-4875 3400);
FORCEPROP 1 LAST NEEDS_NO_SIZE TRUE
J 0
(-4750 2850);
DISPLAY 0.723404 (-4750 2850);
PAINT GREEN (-4750 2850);
DISPLAY INVISIBLE (-4750 2850);
FORCEPROP 1 LAST CDS_LMAN_SYM_OUTLINE -150,200,150,-200
J 0
(-4750 2850);
DISPLAY 0.468085 (-4750 2850);
PAINT GREEN (-4750 2850);
DISPLAY INVISIBLE (-4750 2850);
FORCEPROP 2 LAST CDS_LIB pure_quanta
J 0
(-4750 2850);
DISPLAY INVISIBLE (-4750 2850);
FORCEPROP 1 LAST PATH I63
J 0
(-4750 2850);
DISPLAY 0.723404 (-4750 2850);
PAINT GREEN (-4750 2850);
DISPLAY INVISIBLE (-4750 2850);
FORCEPROP 1 LAST PART_NUMBER AL3CSW12000
J 0
(-4894 3196);
DISPLAY 0.489362 (-4894 3196);
PAINT SKYBLUE (-4894 3196);
DISPLAY INVISIBLE (-4894 3196);
FORCEADD UNIVERSAL_GND..1
(-4250 1075);
FORCEPROP 3 LASTPIN (-4250 1125) SIG_NAME GND\g
J 0
(-4240 1135);
DISPLAY 0.659574 (-4240 1135);
PAINT MONO (-4240 1135);
DISPLAY INVISIBLE (-4240 1135);
FORCEPROP 2 LAST CDS_LIB pure_quanta_power
J 0
(-4250 1075);
DISPLAY INVISIBLE (-4250 1075);
FORCEPROP 1 LAST HDL_POWER GND
J 1
(-4225 1000);
DISPLAY 0.872340 (-4225 1000);
PAINT GREEN (-4225 1000);
DISPLAY INVISIBLE (-4225 1000);
FORCEPROP 1 LAST PATH I64
J 0
(-4175 1075);
DISPLAY 0.872340 (-4175 1075);
PAINT AQUA (-4175 1075);
DISPLAY INVISIBLE (-4175 1075);
FORCEADD UNIVERSAL_GND..1
(-4200 1625);
FORCEPROP 3 LASTPIN (-4200 1675) SIG_NAME GND\g
J 0
(-4190 1685);
DISPLAY 0.659574 (-4190 1685);
PAINT MONO (-4190 1685);
DISPLAY INVISIBLE (-4190 1685);
FORCEPROP 2 LAST CDS_LIB pure_quanta_power
J 2
(-4200 1625);
DISPLAY INVISIBLE (-4200 1625);
FORCEPROP 1 LAST HDL_POWER GND
J 1
(-4175 1550);
DISPLAY 0.872340 (-4175 1550);
PAINT GREEN (-4175 1550);
DISPLAY INVISIBLE (-4175 1550);
FORCEPROP 1 LAST PATH I65
J 0
(-4125 1625);
DISPLAY 0.872340 (-4125 1625);
PAINT AQUA (-4125 1625);
DISPLAY INVISIBLE (-4125 1625);
FORCEADD Q_CAP..1
(-4200 1825);
FORCEPROP 1 LAST LOCATION C1339
J 0
(-4150 1975);
DISPLAY 0.489362 (-4150 1975);
PAINT SKYBLUE (-4150 1975);
FORCEPROP 0 LAST $SEC 1
J 2
(-4150 2000);
DISPLAY 0.680851 (-4150 2000);
PAINT MONO (-4150 2000);
DISPLAY INVISIBLE (-4150 2000);
FORCEPROP 0 LAST CDS_SEC 1
J 2
(-4150 2000);
DISPLAY 1.021277 (-4150 2000);
DISPLAY INVISIBLE (-4150 2000);
FORCEPROP 1 LASTPIN (-4200 1925) $PN 1
J 0
(-4190 1905);
DISPLAY 0.489362 (-4190 1905);
PAINT MONO (-4190 1905);
FORCEPROP 1 LASTPIN (-4200 1725) $PN 2
J 0
(-4190 1705);
DISPLAY 0.489362 (-4190 1705);
PAINT MONO (-4190 1705);
FORCEPROP 1 LAST VALUE 0.1UF
J 0
(-4150 1925);
DISPLAY 0.489362 (-4150 1925);
PAINT SKYBLUE (-4150 1925);
FORCEPROP 1 LAST PACK_TYPE 0402
J 0
(-4150 1725);
DISPLAY 0.489362 (-4150 1725);
PAINT SKYBLUE (-4150 1725);
FORCEPROP 1 LAST MATERIAL X7R
J 0
(-4150 1775);
DISPLAY 0.489362 (-4150 1775);
PAINT SKYBLUE (-4150 1775);
FORCEPROP 1 LAST TOLERANCE 10%
J 0
(-4150 1825);
DISPLAY 0.489362 (-4150 1825);
PAINT SKYBLUE (-4150 1825);
FORCEPROP 1 LAST VOLTAGE 25V
J 0
(-4150 1875);
DISPLAY 0.489362 (-4150 1875);
PAINT SKYBLUE (-4150 1875);
FORCEPROP 2 LAST CDS_LIB pure_quanta
J 2
(-4200 1825);
DISPLAY INVISIBLE (-4200 1825);
FORCEPROP 1 LAST PATH I66
J 0
(-4150 1975);
DISPLAY 0.978723 (-4150 1975);
PAINT WHITE (-4150 1975);
DISPLAY INVISIBLE (-4150 1975);
FORCEPROP 1 LAST PART_NUMBER CH4104K1B00
J 0
(-4150 1675);
DISPLAY 0.489362 (-4150 1675);
PAINT SKYBLUE (-4150 1675);
DISPLAY INVISIBLE (-4150 1675);
FORCEADD UNIVERSAL_POWER..1
R 2
(-4275 2100);
FORCEPROP 3 LASTPIN (-4275 2050) SIG_NAME P3V3_AUX\g
J 0
(-4265 2060);
DISPLAY 0.659574 (-4265 2060);
PAINT MONO (-4265 2060);
DISPLAY INVISIBLE (-4265 2060);
FORCEPROP 1 LAST HDL_POWER P3V3_AUX
J 1
(-4275 2150);
DISPLAY 0.489362 (-4275 2150);
PAINT GREEN (-4275 2150);
FORCEPROP 2 LAST CDS_LIB pure_quanta_power
J 2
(-4275 2100);
DISPLAY INVISIBLE (-4275 2100);
FORCEPROP 1 LAST PATH I67
J 2
(-4325 2125);
DISPLAY 0.872340 (-4325 2125);
PAINT AQUA (-4325 2125);
DISPLAY INVISIBLE (-4325 2125);
FORCEADD PI3CSW12ZUAEX..1
(-4700 1400);
FORCEPROP 1 LAST LOCATION U108
J 0
(-4844 1893);
DISPLAY 0.489362 (-4844 1893);
PAINT SKYBLUE (-4844 1893);
FORCEPROP 0 LAST $SEC 1
J 0
(-4825 2050);
DISPLAY 0.680851 (-4825 2050);
PAINT MONO (-4825 2050);
DISPLAY INVISIBLE (-4825 2050);
FORCEPROP 0 LAST CDS_SEC 1
J 0
(-4825 2050);
DISPLAY 1.021277 (-4825 2050);
DISPLAY INVISIBLE (-4825 2050);
FORCEPROP 0 LASTPIN (-5000 1400) $PN 1
J 2
(-5010 1410);
DISPLAY 0.489362 (-5010 1410);
PAINT MONO (-5010 1410);
FORCEPROP 0 LASTPIN (-5000 1350) $PN 2
J 2
(-5010 1360);
DISPLAY 0.489362 (-5010 1360);
PAINT MONO (-5010 1360);
FORCEPROP 0 LASTPIN (-5000 1300) $PN 3
J 2
(-5010 1310);
DISPLAY 0.489362 (-5010 1310);
PAINT MONO (-5010 1310);
FORCEPROP 0 LASTPIN (-5000 1250) $PN 4
J 2
(-5010 1260);
DISPLAY 0.489362 (-5010 1260);
PAINT MONO (-5010 1260);
FORCEPROP 0 LASTPIN (-4400 1500) $PN 8
J 0
(-4390 1510);
DISPLAY 0.489362 (-4390 1510);
PAINT MONO (-4390 1510);
FORCEPROP 0 LASTPIN (-4400 1450) $PN 7
J 0
(-4390 1460);
DISPLAY 0.489362 (-4390 1460);
PAINT MONO (-4390 1460);
FORCEPROP 0 LASTPIN (-4400 1250) $PN 5
J 0
(-4390 1260);
DISPLAY 0.489362 (-4390 1260);
PAINT MONO (-4390 1260);
FORCEPROP 0 LASTPIN (-5000 1550) $PN 6
J 2
(-5010 1560);
DISPLAY 0.489362 (-5010 1560);
PAINT MONO (-5010 1560);
FORCEPROP 0 LASTPIN (-5000 1500) $PN 9
J 2
(-5010 1510);
DISPLAY 0.489362 (-5010 1510);
PAINT MONO (-5010 1510);
FORCEPROP 0 LASTPIN (-4400 1550) $PN 10
J 0
(-4390 1560);
DISPLAY 0.489362 (-4390 1560);
PAINT MONO (-4390 1560);
FORCEPROP 1 LAST MATERIAL IC
J 0
(-4844 1619);
DISPLAY 0.489362 (-4844 1619);
PAINT SKYBLUE (-4844 1619);
FORCEPROP 2 LAST VALUE PI3CSW12ZUAEX
J 0
(-4825 1950);
DISPLAY 0.489362 (-4825 1950);
PAINT SKYBLUE (-4825 1950);
FORCEPROP 2 LAST PART_TYPE SMLF
J 0
(-4825 2000);
DISPLAY 1.021277 (-4825 2000);
FORCEPROP 2 LAST CDS_LIB pure_quanta
J 0
(-4700 1400);
DISPLAY INVISIBLE (-4700 1400);
FORCEPROP 1 LAST CDS_LMAN_SYM_OUTLINE -150,200,150,-200
J 0
(-4700 1400);
DISPLAY 0.468085 (-4700 1400);
PAINT GREEN (-4700 1400);
DISPLAY INVISIBLE (-4700 1400);
FORCEPROP 1 LAST NEEDS_NO_SIZE TRUE
J 0
(-4700 1400);
DISPLAY 0.723404 (-4700 1400);
PAINT GREEN (-4700 1400);
DISPLAY INVISIBLE (-4700 1400);
FORCEPROP 1 LAST PATH I68
J 0
(-4700 1400);
DISPLAY 0.723404 (-4700 1400);
PAINT GREEN (-4700 1400);
DISPLAY INVISIBLE (-4700 1400);
FORCEPROP 1 LAST PART_NUMBER AL3CSW12000
J 0
(-4844 1746);
DISPLAY 0.489362 (-4844 1746);
PAINT SKYBLUE (-4844 1746);
DISPLAY INVISIBLE (-4844 1746);
FORCEADD OFFPAGE..2
(-1825 4475);
FORCEPROP 2 LAST $XR5 97 
J 0
(-1186 4475);
DISPLAY 0.638298 (-1186 4475);
PAINT MONO (-1186 4475);
FORCEPROP 2 LAST $XR4 96 
J 0
(-1276 4475);
DISPLAY 0.638298 (-1276 4475);
PAINT MONO (-1276 4475);
FORCEPROP 2 LAST $XR3 95 
J 0
(-1366 4475);
DISPLAY 0.638298 (-1366 4475);
PAINT MONO (-1366 4475);
FORCEPROP 2 LAST $XR2 94 
J 0
(-1456 4475);
DISPLAY 0.638298 (-1456 4475);
PAINT MONO (-1456 4475);
FORCEPROP 2 LAST $XR1 93 
J 0
(-1546 4475);
DISPLAY 0.638298 (-1546 4475);
PAINT MONO (-1546 4475);
FORCEPROP 2 LAST $XR0 92 
J 0
(-1636 4475);
DISPLAY 0.638298 (-1636 4475);
PAINT MONO (-1636 4475);
FORCEPROP 2 LAST CDS_LIB standard
J 0
(-1825 4475);
DISPLAY INVISIBLE (-1825 4475);
FORCEPROP 1 LAST OFFPAGE TRUE
J 0
(-1500 4350);
DISPLAY 0.872340 (-1500 4350);
PAINT GREEN (-1500 4350);
DISPLAY INVISIBLE (-1500 4350);
FORCEPROP 1 LAST COMMENT_BODY TRUE
J 0
(-1870 4380);
DISPLAY 0.872340 (-1870 4380);
PAINT GREEN (-1870 4380);
DISPLAY INVISIBLE (-1870 4380);
FORCEPROP 2 LAST PATH I69
J 0
(-1625 4525);
DISPLAY 1.021277 (-1625 4525);
DISPLAY INVISIBLE (-1625 4525);
FORCEADD OFFPAGE..3
(-1825 4425);
FORCEPROP 2 LAST $XR5 97 
J 0
(-1161 4425);
DISPLAY 0.638298 (-1161 4425);
PAINT MONO (-1161 4425);
FORCEPROP 2 LAST $XR4 96 
J 0
(-1251 4425);
DISPLAY 0.638298 (-1251 4425);
PAINT MONO (-1251 4425);
FORCEPROP 2 LAST $XR3 95 
J 0
(-1341 4425);
DISPLAY 0.638298 (-1341 4425);
PAINT MONO (-1341 4425);
FORCEPROP 2 LAST $XR2 94 
J 0
(-1431 4425);
DISPLAY 0.638298 (-1431 4425);
PAINT MONO (-1431 4425);
FORCEPROP 2 LAST $XR1 93 
J 0
(-1521 4425);
DISPLAY 0.638298 (-1521 4425);
PAINT MONO (-1521 4425);
FORCEPROP 2 LAST $XR0 92 
J 0
(-1611 4425);
DISPLAY 0.638298 (-1611 4425);
PAINT MONO (-1611 4425);
FORCEPROP 2 LAST CDS_LIB standard
J 0
(-1825 4425);
DISPLAY INVISIBLE (-1825 4425);
FORCEPROP 1 LAST OFFPAGE TRUE
J 0
(-1500 4300);
DISPLAY 0.872340 (-1500 4300);
PAINT GREEN (-1500 4300);
DISPLAY INVISIBLE (-1500 4300);
FORCEPROP 1 LAST COMMENT_BODY TRUE
J 0
(-1875 4325);
DISPLAY 0.872340 (-1875 4325);
PAINT GREEN (-1875 4325);
DISPLAY INVISIBLE (-1875 4325);
FORCEPROP 2 LAST PATH I70
J 0
(-1600 4475);
DISPLAY 1.021277 (-1600 4475);
DISPLAY INVISIBLE (-1600 4475);
FORCEADD OFFPAGE..2
(-1875 2950);
FORCEPROP 2 LAST $XR5 103 
J 0
(-1146 2950);
DISPLAY 0.638298 (-1146 2950);
PAINT MONO (-1146 2950);
FORCEPROP 2 LAST $XR4 102 
J 0
(-1266 2950);
DISPLAY 0.638298 (-1266 2950);
PAINT MONO (-1266 2950);
FORCEPROP 2 LAST $XR3 101 
J 0
(-1386 2950);
DISPLAY 0.638298 (-1386 2950);
PAINT MONO (-1386 2950);
FORCEPROP 2 LAST $XR2 100 
J 0
(-1506 2950);
DISPLAY 0.638298 (-1506 2950);
PAINT MONO (-1506 2950);
FORCEPROP 2 LAST $XR1 99 
J 0
(-1596 2950);
DISPLAY 0.638298 (-1596 2950);
PAINT MONO (-1596 2950);
FORCEPROP 2 LAST $XR0 98 
J 0
(-1686 2950);
DISPLAY 0.638298 (-1686 2950);
PAINT MONO (-1686 2950);
FORCEPROP 2 LAST CDS_LIB standard
J 0
(-1875 2950);
DISPLAY INVISIBLE (-1875 2950);
FORCEPROP 1 LAST OFFPAGE TRUE
J 0
(-1550 2825);
DISPLAY 0.872340 (-1550 2825);
PAINT GREEN (-1550 2825);
DISPLAY INVISIBLE (-1550 2825);
FORCEPROP 1 LAST COMMENT_BODY TRUE
J 0
(-1920 2855);
DISPLAY 0.872340 (-1920 2855);
PAINT GREEN (-1920 2855);
DISPLAY INVISIBLE (-1920 2855);
FORCEPROP 2 LAST PATH I71
J 0
(-1675 3000);
DISPLAY 1.021277 (-1675 3000);
DISPLAY INVISIBLE (-1675 3000);
FORCEADD OFFPAGE..3
(-1875 2900);
FORCEPROP 2 LAST $XR5 103 
J 0
(-1121 2900);
DISPLAY 0.638298 (-1121 2900);
PAINT MONO (-1121 2900);
FORCEPROP 2 LAST $XR4 102 
J 0
(-1241 2900);
DISPLAY 0.638298 (-1241 2900);
PAINT MONO (-1241 2900);
FORCEPROP 2 LAST $XR3 101 
J 0
(-1361 2900);
DISPLAY 0.638298 (-1361 2900);
PAINT MONO (-1361 2900);
FORCEPROP 2 LAST $XR2 100 
J 0
(-1481 2900);
DISPLAY 0.638298 (-1481 2900);
PAINT MONO (-1481 2900);
FORCEPROP 2 LAST $XR1 99 
J 0
(-1571 2900);
DISPLAY 0.638298 (-1571 2900);
PAINT MONO (-1571 2900);
FORCEPROP 2 LAST $XR0 98 
J 0
(-1661 2900);
DISPLAY 0.638298 (-1661 2900);
PAINT MONO (-1661 2900);
FORCEPROP 2 LAST CDS_LIB standard
J 0
(-1875 2900);
DISPLAY INVISIBLE (-1875 2900);
FORCEPROP 1 LAST OFFPAGE TRUE
J 0
(-1550 2775);
DISPLAY 0.872340 (-1550 2775);
PAINT GREEN (-1550 2775);
DISPLAY INVISIBLE (-1550 2775);
FORCEPROP 1 LAST COMMENT_BODY TRUE
J 0
(-1925 2800);
DISPLAY 0.872340 (-1925 2800);
PAINT GREEN (-1925 2800);
DISPLAY INVISIBLE (-1925 2800);
FORCEPROP 2 LAST PATH I72
J 0
(-1650 2950);
DISPLAY 1.021277 (-1650 2950);
DISPLAY INVISIBLE (-1650 2950);
FORCEADD OFFPAGE..2
(-1850 1500);
FORCEPROP 2 LAST $XR5 109 
J 0
(-1061 1500);
DISPLAY 0.638298 (-1061 1500);
PAINT MONO (-1061 1500);
FORCEPROP 2 LAST $XR4 108 
J 0
(-1181 1500);
DISPLAY 0.638298 (-1181 1500);
PAINT MONO (-1181 1500);
FORCEPROP 2 LAST $XR3 107 
J 0
(-1301 1500);
DISPLAY 0.638298 (-1301 1500);
PAINT MONO (-1301 1500);
FORCEPROP 2 LAST $XR2 106 
J 0
(-1421 1500);
DISPLAY 0.638298 (-1421 1500);
PAINT MONO (-1421 1500);
FORCEPROP 2 LAST $XR1 105 
J 0
(-1541 1500);
DISPLAY 0.638298 (-1541 1500);
PAINT MONO (-1541 1500);
FORCEPROP 2 LAST $XR0 104 
J 0
(-1661 1500);
DISPLAY 0.638298 (-1661 1500);
PAINT MONO (-1661 1500);
FORCEPROP 2 LAST CDS_LIB standard
J 0
(-1850 1500);
DISPLAY INVISIBLE (-1850 1500);
FORCEPROP 1 LAST OFFPAGE TRUE
J 0
(-1525 1375);
DISPLAY 0.872340 (-1525 1375);
PAINT GREEN (-1525 1375);
DISPLAY INVISIBLE (-1525 1375);
FORCEPROP 1 LAST COMMENT_BODY TRUE
J 0
(-1895 1405);
DISPLAY 0.872340 (-1895 1405);
PAINT GREEN (-1895 1405);
DISPLAY INVISIBLE (-1895 1405);
FORCEPROP 2 LAST PATH I73
J 0
(-1650 1550);
DISPLAY 1.021277 (-1650 1550);
DISPLAY INVISIBLE (-1650 1550);
FORCEADD OFFPAGE..3
(-1850 1450);
FORCEPROP 2 LAST $XR5 109 
J 0
(-1036 1450);
DISPLAY 0.638298 (-1036 1450);
PAINT MONO (-1036 1450);
FORCEPROP 2 LAST $XR4 108 
J 0
(-1156 1450);
DISPLAY 0.638298 (-1156 1450);
PAINT MONO (-1156 1450);
FORCEPROP 2 LAST $XR3 107 
J 0
(-1276 1450);
DISPLAY 0.638298 (-1276 1450);
PAINT MONO (-1276 1450);
FORCEPROP 2 LAST $XR2 106 
J 0
(-1396 1450);
DISPLAY 0.638298 (-1396 1450);
PAINT MONO (-1396 1450);
FORCEPROP 2 LAST $XR1 105 
J 0
(-1516 1450);
DISPLAY 0.638298 (-1516 1450);
PAINT MONO (-1516 1450);
FORCEPROP 2 LAST $XR0 104 
J 0
(-1636 1450);
DISPLAY 0.638298 (-1636 1450);
PAINT MONO (-1636 1450);
FORCEPROP 2 LAST CDS_LIB standard
J 0
(-1850 1450);
DISPLAY INVISIBLE (-1850 1450);
FORCEPROP 1 LAST OFFPAGE TRUE
J 0
(-1525 1325);
DISPLAY 0.872340 (-1525 1325);
PAINT GREEN (-1525 1325);
DISPLAY INVISIBLE (-1525 1325);
FORCEPROP 1 LAST COMMENT_BODY TRUE
J 0
(-1900 1350);
DISPLAY 0.872340 (-1900 1350);
PAINT GREEN (-1900 1350);
DISPLAY INVISIBLE (-1900 1350);
FORCEPROP 2 LAST PATH I74
J 0
(-1625 1500);
DISPLAY 1.021277 (-1625 1500);
DISPLAY INVISIBLE (-1625 1500);
FORCEADD Q_RES..1
R 2
(-6075 5775);
FORCEPROP 1 LAST LOCATION R426
J 2
(-6175 5775);
DISPLAY 0.489362 (-6175 5775);
PAINT SKYBLUE (-6175 5775);
FORCEPROP 0 LAST $SEC 1
J 2
(-5800 5825);
DISPLAY 0.680851 (-5800 5825);
PAINT MONO (-5800 5825);
DISPLAY INVISIBLE (-5800 5825);
FORCEPROP 0 LAST CDS_SEC 1
J 2
(-5800 5825);
DISPLAY 1.021277 (-5800 5825);
DISPLAY INVISIBLE (-5800 5825);
FORCEPROP 1 LASTPIN (-5975 5775) $PN 1
J 2
(-5987 5787);
DISPLAY 0.489362 (-5987 5787);
PAINT MONO (-5987 5787);
FORCEPROP 1 LASTPIN (-6175 5775) $PN 2
J 2
(-6137 5787);
DISPLAY 0.489362 (-6137 5787);
PAINT MONO (-6137 5787);
FORCEPROP 1 LAST VALUE 0
J 0
(-5975 5775);
DISPLAY 0.489362 (-5975 5775);
PAINT SKYBLUE (-5975 5775);
FORCEPROP 2 LAST CDS_LIB pure_quanta
J 2
(-6075 5775);
DISPLAY INVISIBLE (-6075 5775);
FORCEPROP 1 LAST WATTAGE 1/16W
J 0
(-6475 5700);
DISPLAY 0.489362 (-6475 5700);
PAINT SKYBLUE (-6475 5700);
DISPLAY INVISIBLE (-6475 5700);
FORCEPROP 1 LAST MATERIAL CHIP
J 2
(-6500 5700);
DISPLAY 0.489362 (-6500 5700);
PAINT SKYBLUE (-6500 5700);
DISPLAY INVISIBLE (-6500 5700);
FORCEPROP 1 LAST TOLERANCE 5%
J 2
(-6050 5700);
DISPLAY 0.489362 (-6050 5700);
PAINT SKYBLUE (-6050 5700);
DISPLAY INVISIBLE (-6050 5700);
FORCEPROP 1 LAST PACK_TYPE 0402LF
J 2
(-6125 5700);
DISPLAY 0.489362 (-6125 5700);
PAINT SKYBLUE (-6125 5700);
DISPLAY INVISIBLE (-6125 5700);
FORCEPROP 1 LAST PATH I99
J 2
(-6025 5925);
DISPLAY 0.978723 (-6025 5925);
PAINT WHITE (-6025 5925);
DISPLAY INVISIBLE (-6025 5925);
FORCEPROP 1 LAST PART_NUMBER CS00002JB13
J 2
(-6100 5825);
DISPLAY 0.489362 (-6100 5825);
PAINT SKYBLUE (-6100 5825);
DISPLAY INVISIBLE (-6100 5825);
FORCEADD CAD_NOTE..1
(-2325 2300);
FORCEPROP 0 LAST NOTE RES R1293.1 & R1334.2 / R1294.1 & R1335.2 CO-LAYOUT
J 0
(-2475 2125);
DISPLAY 0.808511 (-2475 2125);
FORCEPROP 2 LAST CDS_LIB pure_quanta_power
J 0
(-2325 2300);
DISPLAY INVISIBLE (-2325 2300);
FORCEPROP 1 LAST COMMENT_BODY TRUE
J 0
(-2300 2400);
DISPLAY 0.978723 (-2300 2400);
DISPLAY INVISIBLE (-2300 2400);
FORCEADD CAD_NOTE..1
(-2450 3875);
FORCEPROP 0 LAST NOTE RES R1299.1 & R1332.2 / R1300.1 & R1333.2 CO-LAYOUT
J 0
(-2600 3700);
DISPLAY 0.808511 (-2600 3700);
FORCEPROP 2 LAST CDS_LIB pure_quanta_power
J 0
(-2450 3875);
DISPLAY INVISIBLE (-2450 3875);
FORCEPROP 1 LAST COMMENT_BODY TRUE
J 0
(-2425 3975);
DISPLAY 0.978723 (-2425 3975);
DISPLAY INVISIBLE (-2425 3975);
FORCEADD CAD_NOTE..1
(-2550 5325);
FORCEPROP 0 LAST NOTE RES R1297.1 & R1330.2 / R1298.1 & R1331.2 CO-LAYOUT
J 0
(-2700 5150);
DISPLAY 0.808511 (-2700 5150);
FORCEPROP 2 LAST CDS_LIB pure_quanta_power
J 0
(-2550 5325);
DISPLAY INVISIBLE (-2550 5325);
FORCEPROP 1 LAST COMMENT_BODY TRUE
J 0
(-2525 5425);
DISPLAY 0.978723 (-2525 5425);
DISPLAY INVISIBLE (-2525 5425);
FORCEADD DNS..2
(-3475 1725);
PAINT RED (-3475 1725);
FORCEPROP 2 LAST BOM_COST OCP3.0 
J 0
(-3600 1850);
DISPLAY 0.680851 (-3600 1850);
DISPLAY INVISIBLE (-3600 1850);
FORCEPROP 2 LAST CDS_LIB mstr_misc
J 0
(-3475 1725);
DISPLAY INVISIBLE (-3475 1725);
FORCEPROP 1 LAST COMMENT_BODY TRUE
J 0
(-3475 1725);
DISPLAY 0.744681 (-3475 1725);
DISPLAY INVISIBLE (-3475 1725);
FORCEADD DNS..2
(-3700 1725);
PAINT RED (-3700 1725);
FORCEPROP 2 LAST CDS_LIB mstr_misc
J 0
(-3700 1725);
DISPLAY INVISIBLE (-3700 1725);
FORCEPROP 2 LAST BOM_COST OCP3.0 
J 0
(-3825 1850);
DISPLAY 0.680851 (-3825 1850);
DISPLAY INVISIBLE (-3825 1850);
FORCEPROP 1 LAST COMMENT_BODY TRUE
J 0
(-3700 1725);
DISPLAY 0.744681 (-3700 1725);
DISPLAY INVISIBLE (-3700 1725);
FORCEADD DNS..2
(-3475 3175);
PAINT RED (-3475 3175);
FORCEPROP 2 LAST CDS_LIB mstr_misc
J 0
(-3475 3175);
DISPLAY INVISIBLE (-3475 3175);
FORCEPROP 2 LAST BOM_COST OCP3.0 
J 0
(-3600 3300);
DISPLAY 0.680851 (-3600 3300);
DISPLAY INVISIBLE (-3600 3300);
FORCEPROP 1 LAST COMMENT_BODY TRUE
J 0
(-3475 3175);
DISPLAY 0.744681 (-3475 3175);
DISPLAY INVISIBLE (-3475 3175);
FORCEADD DNS..2
(-3700 3175);
PAINT RED (-3700 3175);
FORCEPROP 2 LAST CDS_LIB mstr_misc
J 0
(-3700 3175);
DISPLAY INVISIBLE (-3700 3175);
FORCEPROP 2 LAST BOM_COST OCP3.0 
J 0
(-3825 3300);
DISPLAY 0.680851 (-3825 3300);
DISPLAY INVISIBLE (-3825 3300);
FORCEPROP 1 LAST COMMENT_BODY TRUE
J 0
(-3700 3175);
DISPLAY 0.744681 (-3700 3175);
DISPLAY INVISIBLE (-3700 3175);
FORCEADD DNS..2
(-3475 4700);
PAINT RED (-3475 4700);
FORCEPROP 2 LAST CDS_LIB mstr_misc
J 0
(-3475 4700);
DISPLAY INVISIBLE (-3475 4700);
FORCEPROP 2 LAST BOM_COST OCP3.0 
J 0
(-3600 4825);
DISPLAY 0.680851 (-3600 4825);
DISPLAY INVISIBLE (-3600 4825);
FORCEPROP 1 LAST COMMENT_BODY TRUE
J 0
(-3475 4700);
DISPLAY 0.744681 (-3475 4700);
DISPLAY INVISIBLE (-3475 4700);
FORCEADD DNS..2
(-3700 4700);
PAINT RED (-3700 4700);
FORCEPROP 2 LAST CDS_LIB mstr_misc
J 0
(-3700 4700);
DISPLAY INVISIBLE (-3700 4700);
FORCEPROP 2 LAST BOM_COST OCP3.0 
J 0
(-3825 4825);
DISPLAY 0.680851 (-3825 4825);
DISPLAY INVISIBLE (-3825 4825);
FORCEPROP 1 LAST COMMENT_BODY TRUE
J 0
(-3700 4700);
DISPLAY 0.744681 (-3700 4700);
DISPLAY INVISIBLE (-3700 4700);
FORCEADD DNS..2
(-3500 6100);
PAINT RED (-3500 6100);
FORCEPROP 2 LAST CDS_LIB mstr_misc
J 0
(-3500 6100);
DISPLAY INVISIBLE (-3500 6100);
FORCEPROP 2 LAST BOM_COST OCP3.0 
J 0
(-3625 6225);
DISPLAY 0.680851 (-3625 6225);
DISPLAY INVISIBLE (-3625 6225);
FORCEPROP 1 LAST COMMENT_BODY TRUE
J 0
(-3500 6100);
DISPLAY 0.744681 (-3500 6100);
DISPLAY INVISIBLE (-3500 6100);
FORCEADD DNS..2
(-3700 6100);
PAINT RED (-3700 6100);
FORCEPROP 2 LAST BOM_COST OCP3.0 
J 0
(-3825 6225);
DISPLAY 0.680851 (-3825 6225);
DISPLAY INVISIBLE (-3825 6225);
FORCEPROP 2 LAST CDS_LIB mstr_misc
J 0
(-3700 6100);
DISPLAY INVISIBLE (-3700 6100);
FORCEPROP 1 LAST COMMENT_BODY TRUE
J 0
(-3700 6100);
DISPLAY 0.744681 (-3700 6100);
DISPLAY INVISIBLE (-3700 6100);
FORCEADD DNS..2
(-3050 5300);
PAINT RED (-3050 5300);
FORCEPROP 2 LAST CDS_LIB mstr_misc
J 0
(-3050 5300);
DISPLAY INVISIBLE (-3050 5300);
FORCEPROP 2 LAST BOM_COST OCP3.0 
J 0
(-3175 5425);
DISPLAY 0.680851 (-3175 5425);
DISPLAY INVISIBLE (-3175 5425);
FORCEPROP 1 LAST COMMENT_BODY TRUE
J 0
(-3050 5300);
DISPLAY 0.744681 (-3050 5300);
DISPLAY INVISIBLE (-3050 5300);
FORCEADD DNS..2
(-5425 1725);
PAINT RED (-5425 1725);
FORCEPROP 2 LAST CDS_LIB mstr_misc
J 0
(-5425 1725);
DISPLAY INVISIBLE (-5425 1725);
FORCEPROP 2 LAST BOM_COST OCP3.0 
J 0
(-5550 1850);
DISPLAY 0.680851 (-5550 1850);
DISPLAY INVISIBLE (-5550 1850);
FORCEPROP 1 LAST COMMENT_BODY TRUE
J 0
(-5425 1725);
DISPLAY 0.744681 (-5425 1725);
DISPLAY INVISIBLE (-5425 1725);
FORCEADD DNS..2
(-5625 1725);
PAINT RED (-5625 1725);
FORCEPROP 2 LAST CDS_LIB mstr_misc
J 0
(-5625 1725);
DISPLAY INVISIBLE (-5625 1725);
FORCEPROP 2 LAST BOM_COST OCP3.0 
J 0
(-5750 1850);
DISPLAY 0.680851 (-5750 1850);
DISPLAY INVISIBLE (-5750 1850);
FORCEPROP 1 LAST COMMENT_BODY TRUE
J 0
(-5625 1725);
DISPLAY 0.744681 (-5625 1725);
DISPLAY INVISIBLE (-5625 1725);
FORCEADD DNS..2
(-5425 3175);
PAINT RED (-5425 3175);
FORCEPROP 2 LAST CDS_LIB mstr_misc
J 0
(-5425 3175);
DISPLAY INVISIBLE (-5425 3175);
FORCEPROP 2 LAST BOM_COST OCP3.0 
J 0
(-5550 3300);
DISPLAY 0.680851 (-5550 3300);
DISPLAY INVISIBLE (-5550 3300);
FORCEPROP 1 LAST COMMENT_BODY TRUE
J 0
(-5425 3175);
DISPLAY 0.744681 (-5425 3175);
DISPLAY INVISIBLE (-5425 3175);
FORCEADD DNS..2
(-5625 3175);
PAINT RED (-5625 3175);
FORCEPROP 2 LAST CDS_LIB mstr_misc
J 0
(-5625 3175);
DISPLAY INVISIBLE (-5625 3175);
FORCEPROP 2 LAST BOM_COST OCP3.0 
J 0
(-5750 3300);
DISPLAY 0.680851 (-5750 3300);
DISPLAY INVISIBLE (-5750 3300);
FORCEPROP 1 LAST COMMENT_BODY TRUE
J 0
(-5625 3175);
DISPLAY 0.744681 (-5625 3175);
DISPLAY INVISIBLE (-5625 3175);
FORCEADD DNS..2
(-5450 4675);
PAINT RED (-5450 4675);
FORCEPROP 2 LAST CDS_LIB mstr_misc
J 0
(-5450 4675);
DISPLAY INVISIBLE (-5450 4675);
FORCEPROP 2 LAST BOM_COST OCP3.0 
J 0
(-5575 4800);
DISPLAY 0.680851 (-5575 4800);
DISPLAY INVISIBLE (-5575 4800);
FORCEPROP 1 LAST COMMENT_BODY TRUE
J 0
(-5450 4675);
DISPLAY 0.744681 (-5450 4675);
DISPLAY INVISIBLE (-5450 4675);
FORCEADD DNS..2
(-5650 4675);
PAINT RED (-5650 4675);
FORCEPROP 2 LAST CDS_LIB mstr_misc
J 0
(-5650 4675);
DISPLAY INVISIBLE (-5650 4675);
FORCEPROP 2 LAST BOM_COST OCP3.0 
J 0
(-5775 4800);
DISPLAY 0.680851 (-5775 4800);
DISPLAY INVISIBLE (-5775 4800);
FORCEPROP 1 LAST COMMENT_BODY TRUE
J 0
(-5650 4675);
DISPLAY 0.744681 (-5650 4675);
DISPLAY INVISIBLE (-5650 4675);
FORCEADD DNS..2
(-5425 6175);
PAINT RED (-5425 6175);
FORCEPROP 2 LAST CDS_LIB mstr_misc
J 0
(-5425 6175);
DISPLAY INVISIBLE (-5425 6175);
FORCEPROP 2 LAST BOM_COST OCP3.0 
J 0
(-5550 6300);
DISPLAY 0.680851 (-5550 6300);
DISPLAY INVISIBLE (-5550 6300);
FORCEPROP 1 LAST COMMENT_BODY TRUE
J 0
(-5425 6175);
DISPLAY 0.744681 (-5425 6175);
DISPLAY INVISIBLE (-5425 6175);
FORCEADD DNS..2
(-5625 6175);
PAINT RED (-5625 6175);
FORCEPROP 2 LAST CDS_LIB mstr_misc
J 0
(-5625 6175);
DISPLAY INVISIBLE (-5625 6175);
FORCEPROP 2 LAST BOM_COST OCP3.0 
J 0
(-5750 6300);
DISPLAY 0.680851 (-5750 6300);
DISPLAY INVISIBLE (-5750 6300);
FORCEPROP 1 LAST COMMENT_BODY TRUE
J 0
(-5625 6175);
DISPLAY 0.744681 (-5625 6175);
DISPLAY INVISIBLE (-5625 6175);
FORCEADD DNS..2
(-5925 5325);
PAINT RED (-5925 5325);
FORCEPROP 2 LAST BOM_COST OCP3.0 
J 0
(-6050 5450);
DISPLAY 0.680851 (-6050 5450);
DISPLAY INVISIBLE (-6050 5450);
FORCEPROP 2 LAST CDS_LIB mstr_misc
J 0
(-5925 5325);
DISPLAY INVISIBLE (-5925 5325);
FORCEPROP 1 LAST COMMENT_BODY TRUE
J 0
(-5925 5325);
DISPLAY 0.744681 (-5925 5325);
DISPLAY INVISIBLE (-5925 5325);
FORCEADD DNS..2
(-5775 950);
PAINT RED (-5775 950);
FORCEPROP 2 LAST BOM_COST OCP3.0 
J 0
(-5900 1075);
DISPLAY 0.680851 (-5900 1075);
DISPLAY INVISIBLE (-5900 1075);
FORCEPROP 2 LAST CDS_LIB mstr_misc
J 0
(-5775 950);
DISPLAY INVISIBLE (-5775 950);
FORCEPROP 1 LAST COMMENT_BODY TRUE
J 0
(-5775 950);
DISPLAY 0.744681 (-5775 950);
DISPLAY INVISIBLE (-5775 950);
FORCEADD DNS..2
(-5875 3925);
PAINT RED (-5875 3925);
FORCEPROP 2 LAST CDS_LIB mstr_misc
J 0
(-5875 3925);
DISPLAY INVISIBLE (-5875 3925);
FORCEPROP 2 LAST BOM_COST OCP3.0 
J 0
(-6000 4050);
DISPLAY 0.680851 (-6000 4050);
DISPLAY INVISIBLE (-6000 4050);
FORCEPROP 1 LAST COMMENT_BODY TRUE
J 0
(-5875 3925);
DISPLAY 0.744681 (-5875 3925);
DISPLAY INVISIBLE (-5875 3925);
FORCEADD DNS..2
(-3000 3900);
PAINT RED (-3000 3900);
FORCEPROP 2 LAST CDS_LIB mstr_misc
J 0
(-3000 3900);
DISPLAY INVISIBLE (-3000 3900);
FORCEPROP 2 LAST BOM_COST OCP3.0 
J 0
(-3125 4025);
DISPLAY 0.680851 (-3125 4025);
DISPLAY INVISIBLE (-3125 4025);
FORCEPROP 1 LAST COMMENT_BODY TRUE
J 0
(-3000 3900);
DISPLAY 0.744681 (-3000 3900);
DISPLAY INVISIBLE (-3000 3900);
FORCEADD DNS..2
(-2950 2375);
PAINT RED (-2950 2375);
FORCEPROP 2 LAST BOM_COST OCP3.0 
J 0
(-3075 2500);
DISPLAY 0.680851 (-3075 2500);
DISPLAY INVISIBLE (-3075 2500);
FORCEPROP 2 LAST CDS_LIB mstr_misc
J 0
(-2950 2375);
DISPLAY INVISIBLE (-2950 2375);
FORCEPROP 1 LAST COMMENT_BODY TRUE
J 0
(-2950 2375);
DISPLAY 0.744681 (-2950 2375);
DISPLAY INVISIBLE (-2950 2375);
FORCEADD DNS..2
(-5825 2400);
PAINT RED (-5825 2400);
FORCEPROP 2 LAST BOM_COST OCP3.0 
J 0
(-5950 2525);
DISPLAY 0.680851 (-5950 2525);
DISPLAY INVISIBLE (-5950 2525);
FORCEPROP 2 LAST CDS_LIB mstr_misc
J 0
(-5825 2400);
DISPLAY INVISIBLE (-5825 2400);
FORCEPROP 1 LAST COMMENT_BODY TRUE
J 0
(-5825 2400);
DISPLAY 0.744681 (-5825 2400);
DISPLAY INVISIBLE (-5825 2400);
FORCEADD QUANTA_TITLE_BLOCK_C..1
(0 0);
FORCEPROP 0 LAST CDS_CON_LAST_MODIFIED Thu Sep 14 16:12:14 2023
J 0
(-1885 15);
DISPLAY INVISIBLE (-1885 15);
FORCEPROP 1 LAST CUSTOM_TXT_CDS <CON_LAST_MODIFIED>
J 0
(-1885 15);
DISPLAY 0.978723 (-1885 15);
FORCEPROP 2 LAST CUSTOM_TXT_CDS <XR_PAGE_TITLE>
J 0
(-7890 5250);
DISPLAY 0.638298 (-7890 5250);
PAINT PINK (-7890 5250);
DISPLAY INVISIBLE (-7890 5250);
FORCEPROP 1 LAST CUSTOM_TXT_CDS <NAME_2>
J 0
(-3175 50);
FORCEPROP 1 LAST CUSTOM_TXT_CDS <NAME_1>
J 0
(-3175 175);
FORCEPROP 1 LAST CUSTOM_TXT_CDS <Q_NUMBER>
J 0
(-1403 103);
DISPLAY 1.212766 (-1403 103);
FORCEPROP 1 LAST CUSTOM_TXT_CDS <Q_PROJ>
J 0
(-2382 102);
DISPLAY 1.212766 (-2382 102);
FORCEPROP 1 LAST CUSTOM_TXT_CDS <Q_REV>
J 0
(-184 103);
DISPLAY 1.212766 (-184 103);
FORCEPROP 1 LAST CUSTOM_TXT_CDS <CON_PAGE_NUM> OF <CON_TOTAL_PAGES>
J 0
(-446 18);
DISPLAY 0.978723 (-446 18);
FORCEPROP 1 LAST Q_TITLE I3C MUX - DDR5 SPD
J 0
(-9250 75);
DISPLAY 2.446809 (-9250 75);
PAINT GREEN (-9250 75);
FORCEPROP 2 LAST PAGE_BORDER TRUE
J 0
(-7890 5250);
DISPLAY 0.638298 (-7890 5250);
PAINT PINK (-7890 5250);
DISPLAY INVISIBLE (-7890 5250);
FORCEPROP 1 LAST CDS_LMAN_SYM_OUTLINE -9475,6775,100,-125
J 0
(0 0);
DISPLAY 0.468085 (0 0);
PAINT GREEN (0 0);
DISPLAY INVISIBLE (0 0);
FORCEPROP 2 LAST CDS_LIB pure_quanta
J 0
(0 0);
DISPLAY INVISIBLE (0 0);
FORCEPROP 2 LAST CDS_XR_PAGE_TITLE CR-159 : @T6G_MB_LIB.T6G(SCH_1):PAGE159
J 0
(-7890 5250);
DISPLAY 0.638298 (-7890 5250);
PAINT PINK (-7890 5250);
DISPLAY INVISIBLE (-7890 5250);
FORCEPROP 1 LAST Q_DEPT BU9
J 1
(-3700 -25);
DISPLAY 1.957447 (-3700 -25);
PAINT GREEN (-3700 -25);
DISPLAY INVISIBLE (-3700 -25);
FORCEPROP 1 LAST COMMENT_BODY TRUE
J 0
(12 -13);
DISPLAY 0.978723 (12 -13);
PAINT GREEN (12 -13);
DISPLAY INVISIBLE (12 -13);
FORCEADD DNS..2
(-2900 925);
PAINT RED (-2900 925);
FORCEPROP 2 LAST CDS_LIB mstr_misc
J 0
(-2900 925);
DISPLAY INVISIBLE (-2900 925);
FORCEPROP 2 LAST BOM_COST OCP3.0 
J 0
(-3025 1050);
DISPLAY 0.680851 (-3025 1050);
DISPLAY INVISIBLE (-3025 1050);
FORCEPROP 1 LAST COMMENT_BODY TRUE
J 0
(-2900 925);
DISPLAY 0.744681 (-2900 925);
DISPLAY INVISIBLE (-2900 925);
FORCEADD CAD_NOTE..1
(-8150 3750);
FORCEPROP 0 LAST NOTE CPU I3C BYPASS, RES R428.2 & R986.1 / R429.2 & R987.1 CO-LAYOUT
J 0
(-8300 3575);
DISPLAY 0.808511 (-8300 3575);
FORCEPROP 2 LAST CDS_LIB pure_quanta_power
J 0
(-8150 3750);
DISPLAY INVISIBLE (-8150 3750);
FORCEPROP 1 LAST COMMENT_BODY TRUE
J 0
(-8125 3850);
DISPLAY 0.978723 (-8125 3850);
DISPLAY INVISIBLE (-8125 3850);
FORCEADD CAD_NOTE..1
(-8100 5250);
FORCEPROP 0 LAST NOTE CPU I3C BYPASS, RES R426.2 & R2310.1 / R427.2 & R2311.1 CO-LAYOUT
J 0
(-8250 5075);
DISPLAY 0.808511 (-8250 5075);
FORCEPROP 2 LAST CDS_LIB pure_quanta_power
J 0
(-8100 5250);
DISPLAY INVISIBLE (-8100 5250);
FORCEPROP 1 LAST COMMENT_BODY TRUE
J 0
(-8075 5350);
DISPLAY 0.978723 (-8075 5350);
DISPLAY INVISIBLE (-8075 5350);
FORCEADD CAD_NOTE..1
(-8100 2225);
FORCEPROP 0 LAST NOTE CPU I3C BYPASS, RES R564.2 & R988.1 / R565.2 & R989.1 CO-LAYOUT
J 0
(-8250 2050);
DISPLAY 0.808511 (-8250 2050);
FORCEPROP 2 LAST CDS_LIB pure_quanta_power
J 0
(-8100 2225);
DISPLAY INVISIBLE (-8100 2225);
FORCEPROP 1 LAST COMMENT_BODY TRUE
J 0
(-8075 2325);
DISPLAY 0.978723 (-8075 2325);
DISPLAY INVISIBLE (-8075 2325);
FORCEADD CAD_NOTE..1
(-6475 650);
FORCEPROP 0 LAST NOTE CPU I3C BYPASS, RES R566.2 & R990.1 / R567.2 & R991.1 CO-LAYOUT
J 0
(-6625 475);
DISPLAY 0.808511 (-6625 475);
FORCEPROP 2 LAST CDS_LIB pure_quanta_power
J 0
(-6475 650);
DISPLAY INVISIBLE (-6475 650);
FORCEPROP 1 LAST COMMENT_BODY TRUE
J 0
(-6450 750);
DISPLAY 0.978723 (-6450 750);
DISPLAY INVISIBLE (-6450 750);
FORCEADD CAD_NOTE..1
(-2425 775);
FORCEPROP 0 LAST NOTE RES R1295.1 & R1336.2 / R1296.1& R1337.2 CO-LAYOUT
J 0
(-2575 600);
DISPLAY 0.808511 (-2575 600);
FORCEPROP 2 LAST CDS_LIB pure_quanta_power
J 0
(-2425 775);
DISPLAY INVISIBLE (-2425 775);
FORCEPROP 1 LAST COMMENT_BODY TRUE
J 0
(-2400 875);
DISPLAY 0.978723 (-2400 875);
DISPLAY INVISIBLE (-2400 875);
WIRE 16 -1 (-4475 5625)(-4325 5625);
WIRE 16 -1 (-4325 5625)(-4325 5500);
WIRE 16 -1 (-4275 6100)(-4275 6050);
WIRE 16 -1 (-4250 4700)(-4250 4650);
WIRE 16 -1 (-4450 4225)(-4300 4225);
WIRE 16 -1 (-4300 4225)(-4300 4100);
WIRE 16 -1 (-4450 2700)(-4300 2700);
WIRE 16 -1 (-4300 2700)(-4300 2575);
WIRE 16 -1 (-4250 3175)(-4250 3125);
WIRE 16 -1 (-4400 1250)(-4250 1250);
WIRE 16 -1 (-4250 1250)(-4250 1125);
WIRE 16 -1 (-4200 1725)(-4200 1675);
WIRE 16 -1 (-1900 1450)(-2675 1450);
FORCEPROP 2 LAST SIG_NAME I3C_SPD_DDRGL_CPU1_SDA
J 2
(-1925 1460);
DISPLAY 0.489362 (-1925 1460);
WIRE 16 -1 (-2675 1450)(-2675 900);
WIRE 16 -1 (-2675 1450)(-3075 1450);
WIRE 16 -1 (-2675 900)(-2925 900);
WIRE 16 -1 (-5850 950)(-3125 950);
FORCEPROP 2 LAST SIG_NAME I3C_SPD_DDRGL_CPU1_BYPASS_SCL
J 0
(-4900 960);
DISPLAY 0.489362 (-4900 960);
FORCEPROP 2 LASTPROP $XRERR UNIQUE?
J 0
(-5140 960);
DISPLAY 0.638298 (-5140 960);
PAINT MONO (-5140 960);
DISPLAY INVISIBLE (-5140 960);
WIRE 16 -1 (-2750 950)(-2750 1500);
WIRE 16 -1 (-2750 950)(-2925 950);
WIRE 16 -1 (-1900 1500)(-2750 1500);
FORCEPROP 2 LAST SIG_NAME I3C_SPD_DDRGL_CPU1_SCL
J 2
(-1925 1510);
DISPLAY 0.489362 (-1925 1510);
WIRE 16 -1 (-2750 1500)(-3075 1500);
WIRE 16 -1 (-3125 900)(-5850 900);
FORCEPROP 2 LAST SIG_NAME I3C_SPD_DDRGL_CPU1_BYPASS_SDA
J 0
(-4900 910);
DISPLAY 0.489362 (-4900 910);
FORCEPROP 2 LASTPROP $XRERR UNIQUE?
J 0
(-5140 910);
DISPLAY 0.638298 (-5140 910);
PAINT MONO (-5140 910);
DISPLAY INVISIBLE (-5140 910);
WIRE 16 -1 (-6325 900)(-6050 900);
WIRE 16 -1 (-6325 1350)(-6325 900);
WIRE 16 -1 (-6075 1350)(-6325 1350);
FORCEPROP 2 LAST SIG_NAME I3C_1_SPD_DDRGL_CPU1_R_SDA
J 2
(-6310 1360);
DISPLAY 0.489362 (-6310 1360);
WIRE 16 -1 (-6325 1350)(-6975 1350);
WIRE 16 -1 (-6275 950)(-6050 950);
WIRE 16 -1 (-6275 1400)(-6275 950);
WIRE 16 -1 (-6075 1400)(-6275 1400);
WIRE 16 -1 (-6275 1400)(-6975 1400);
FORCEPROP 2 LAST SIG_NAME I3C_1_SPD_DDRGL_CPU1_R_SCL
J 2
(-6310 1410);
DISPLAY 0.489362 (-6310 1410);
WIRE 16 -1 (-5850 1550)(-5000 1550);
FORCEPROP 2 LAST SIG_NAME FM_I3C_CPU1_MUX1_OE_N
J 0
(-5660 1560);
DISPLAY 0.489362 (-5660 1560);
WIRE 16 -1 (-3175 2350)(-5900 2350);
FORCEPROP 2 LAST SIG_NAME I3C_SPD_DDRAF_CPU1_BYPASS_SDA
J 0
(-4950 2360);
DISPLAY 0.489362 (-4950 2360);
FORCEPROP 2 LASTPROP $XRERR UNIQUE?
J 0
(-5190 2360);
DISPLAY 0.638298 (-5190 2360);
PAINT MONO (-5190 2360);
DISPLAY INVISIBLE (-5190 2360);
WIRE 16 -1 (-5900 2400)(-3175 2400);
FORCEPROP 2 LAST SIG_NAME I3C_SPD_DDRAF_CPU1_BYPASS_SCL
J 0
(-4950 2410);
DISPLAY 0.489362 (-4950 2410);
FORCEPROP 2 LASTPROP $XRERR UNIQUE?
J 0
(-5190 2410);
DISPLAY 0.638298 (-5190 2410);
PAINT MONO (-5190 2410);
DISPLAY INVISIBLE (-5190 2410);
WIRE 16 -1 (-2800 2400)(-2800 2950);
WIRE 16 -1 (-2800 2400)(-2975 2400);
WIRE 16 -1 (-1925 2950)(-2800 2950);
FORCEPROP 2 LAST SIG_NAME I3C_SPD_DDRAF_CPU1_SCL
J 2
(-1925 2960);
DISPLAY 0.489362 (-1925 2960);
WIRE 16 -1 (-2800 2950)(-3100 2950);
WIRE 16 -1 (-1925 2900)(-2725 2900);
FORCEPROP 2 LAST SIG_NAME I3C_SPD_DDRAF_CPU1_SDA
J 2
(-1925 2910);
DISPLAY 0.489362 (-1925 2910);
WIRE 16 -1 (-2725 2900)(-2725 2350);
WIRE 16 -1 (-2725 2900)(-3100 2900);
WIRE 16 -1 (-2725 2350)(-2975 2350);
WIRE 16 -1 (-4275 2050)(-4275 2000);
WIRE 16 -1 (-4200 2000)(-4275 2000);
WIRE 16 -1 (-4275 2000)(-4275 1550);
WIRE 16 -1 (-4275 1550)(-4400 1550);
WIRE 16 -1 (-4200 1925)(-4200 2000);
WIRE 16 -1 (-4325 3500)(-4325 3450);
WIRE 16 -1 (-4250 3450)(-4325 3450);
WIRE 16 -1 (-4325 3450)(-4325 3000);
WIRE 16 -1 (-4325 3000)(-4450 3000);
WIRE 16 -1 (-4250 3375)(-4250 3450);
WIRE 16 -1 (-4325 5025)(-4325 4975);
WIRE 16 -1 (-4250 4975)(-4325 4975);
WIRE 16 -1 (-4325 4975)(-4325 4525);
WIRE 16 -1 (-4325 4525)(-4450 4525);
WIRE 16 -1 (-4250 4900)(-4250 4975);
WIRE 16 -1 (-4350 6425)(-4350 6375);
WIRE 16 -1 (-4275 6375)(-4350 6375);
WIRE 16 -1 (-4350 6375)(-4350 5925);
WIRE 16 -1 (-4350 5925)(-4475 5925);
WIRE 16 -1 (-4275 6300)(-4275 6375);
WIRE 16 -1 (-5650 1850)(-5450 1850);
WIRE 16 -1 (-5650 1850)(-5650 1825);
WIRE 16 -1 (-5450 1825)(-5450 1850);
WIRE 16 -1 (-5450 1850)(-5450 1875);
WIRE 16 -1 (-5650 3300)(-5450 3300);
WIRE 16 -1 (-5650 3300)(-5650 3275);
WIRE 16 -1 (-5450 3275)(-5450 3300);
WIRE 16 -1 (-5450 3300)(-5450 3325);
WIRE 16 -1 (-5650 4825)(-5450 4825);
WIRE 16 -1 (-5650 4825)(-5650 4800);
WIRE 16 -1 (-5450 4800)(-5450 4825);
WIRE 16 -1 (-5450 4825)(-5450 4850);
WIRE 16 -1 (-5650 6375)(-5450 6375);
WIRE 16 -1 (-5650 6375)(-5650 6275);
WIRE 16 -1 (-5450 6375)(-5450 6425);
WIRE 16 -1 (-5450 6275)(-5450 6375);
WIRE 16 -1 (-3650 1900)(-3450 1900);
WIRE 16 -1 (-3650 1900)(-3650 1825);
WIRE 16 -1 (-3450 1900)(-3450 1950);
WIRE 16 -1 (-3450 1825)(-3450 1900);
WIRE 16 -1 (-3650 3350)(-3450 3350);
WIRE 16 -1 (-3650 3350)(-3650 3275);
WIRE 16 -1 (-3450 3350)(-3450 3400);
WIRE 16 -1 (-3450 3275)(-3450 3350);
WIRE 16 -1 (-3450 4925)(-3450 4875);
WIRE 16 -1 (-3450 4875)(-3450 4800);
WIRE 16 -1 (-3450 4875)(-3650 4875);
WIRE 16 -1 (-3650 4875)(-3650 4800);
WIRE 16 -1 (-3650 6275)(-3450 6275);
WIRE 16 -1 (-3650 6275)(-3650 6200);
WIRE 16 -1 (-3450 6275)(-3450 6325);
WIRE 16 -1 (-3450 6200)(-3450 6275);
WIRE 16 -1 (-6150 2850)(-6325 2850);
WIRE 16 -1 (-6325 2850)(-6325 2400);
WIRE 16 -1 (-6325 2850)(-7050 2850);
FORCEPROP 2 LAST SIG_NAME I3C_0_SPD_DDRAF_CPU1_R_SCL
J 2
(-6385 2860);
DISPLAY 0.489362 (-6385 2860);
WIRE 16 -1 (-6325 2400)(-6100 2400);
WIRE 16 -1 (-6150 2800)(-6375 2800);
WIRE 16 -1 (-6375 2800)(-6375 2350);
WIRE 16 -1 (-6375 2800)(-7050 2800);
FORCEPROP 2 LAST SIG_NAME I3C_0_SPD_DDRAF_CPU1_R_SDA
J 2
(-6385 2810);
DISPLAY 0.489362 (-6385 2810);
WIRE 16 -1 (-6375 2350)(-6100 2350);
WIRE 16 -1 (-1875 4425)(-2775 4425);
FORCEPROP 2 LAST SIG_NAME I3C_SPD_DDRGL_CPU0_SDA
J 2
(-1925 4435);
DISPLAY 0.489362 (-1925 4435);
WIRE 16 -1 (-2775 4425)(-3050 4425);
WIRE 16 -1 (-2775 4425)(-2775 3875);
WIRE 16 -1 (-2775 3875)(-3025 3875);
WIRE 16 -1 (-5950 3925)(-3225 3925);
FORCEPROP 2 LAST SIG_NAME I3C_SPD_DDRGL_CPU0_BYPASS_SCL
J 0
(-5000 3935);
DISPLAY 0.489362 (-5000 3935);
FORCEPROP 2 LASTPROP $XRERR UNIQUE?
J 0
(-5240 3935);
DISPLAY 0.638298 (-5240 3935);
PAINT MONO (-5240 3935);
DISPLAY INVISIBLE (-5240 3935);
WIRE 16 -1 (-3225 3875)(-5950 3875);
FORCEPROP 2 LAST SIG_NAME I3C_SPD_DDRGL_CPU0_BYPASS_SDA
J 0
(-5000 3885);
DISPLAY 0.489362 (-5000 3885);
FORCEPROP 2 LASTPROP $XRERR UNIQUE?
J 0
(-5240 3885);
DISPLAY 0.638298 (-5240 3885);
PAINT MONO (-5240 3885);
DISPLAY INVISIBLE (-5240 3885);
WIRE 16 -1 (-1875 4475)(-2850 4475);
FORCEPROP 2 LAST SIG_NAME I3C_SPD_DDRGL_CPU0_SCL
J 2
(-1925 4485);
DISPLAY 0.489362 (-1925 4485);
WIRE 16 -1 (-2850 4475)(-3050 4475);
WIRE 16 -1 (-2850 3925)(-2850 4475);
WIRE 16 -1 (-2850 3925)(-3025 3925);
WIRE 16 -1 (-6150 4325)(-6425 4325);
WIRE 16 -1 (-6425 4325)(-7050 4325);
FORCEPROP 2 LAST SIG_NAME I3C_1_SPD_DDRGL_CPU0_R_SDA
J 2
(-6460 4335);
DISPLAY 0.489362 (-6460 4335);
WIRE 16 -1 (-6425 4325)(-6425 3875);
WIRE 16 -1 (-6425 3875)(-6150 3875);
WIRE 16 -1 (-6150 4375)(-6375 4375);
WIRE 16 -1 (-6375 4375)(-7050 4375);
FORCEPROP 2 LAST SIG_NAME I3C_1_SPD_DDRGL_CPU0_R_SCL
J 2
(-6460 4385);
DISPLAY 0.489362 (-6460 4385);
WIRE 16 -1 (-6375 4375)(-6375 3925);
WIRE 16 -1 (-6375 3925)(-6150 3925);
WIRE 16 -1 (-1875 5825)(-2825 5825);
FORCEPROP 2 LAST SIG_NAME I3C_SPD_DDRAF_CPU0_SDA
J 2
(-1925 5835);
DISPLAY 0.489362 (-1925 5835);
WIRE 16 -1 (-2825 5825)(-3050 5825);
WIRE 16 -1 (-2825 5825)(-2825 5275);
WIRE 16 -1 (-2825 5275)(-3075 5275);
WIRE 16 -1 (-1875 5875)(-2900 5875);
FORCEPROP 2 LAST SIG_NAME I3C_SPD_DDRAF_CPU0_SCL
J 2
(-1925 5885);
DISPLAY 0.489362 (-1925 5885);
WIRE 16 -1 (-2900 5875)(-3050 5875);
WIRE 16 -1 (-2900 5325)(-2900 5875);
WIRE 16 -1 (-2900 5325)(-3075 5325);
WIRE 16 -1 (-3275 5275)(-6000 5275);
FORCEPROP 2 LAST SIG_NAME I3C_SPD_DDRAF_CPU0_BYPASS_SDA
J 0
(-5050 5285);
DISPLAY 0.489362 (-5050 5285);
FORCEPROP 2 LASTPROP $XRERR UNIQUE?
J 0
(-5290 5285);
DISPLAY 0.638298 (-5290 5285);
PAINT MONO (-5290 5285);
DISPLAY INVISIBLE (-5290 5285);
WIRE 16 -1 (-6175 5725)(-6475 5725);
WIRE 16 -1 (-6475 5725)(-6475 5275);
WIRE 16 -1 (-6475 5725)(-7075 5725);
FORCEPROP 2 LAST SIG_NAME I3C_0_SPD_DDRAF_CPU0_R_SDA
J 2
(-6485 5735);
DISPLAY 0.489362 (-6485 5735);
WIRE 16 -1 (-6475 5275)(-6200 5275);
WIRE 16 -1 (-6175 5775)(-6425 5775);
WIRE 16 -1 (-6425 5775)(-6425 5325);
WIRE 16 -1 (-6425 5775)(-7075 5775);
FORCEPROP 2 LAST SIG_NAME I3C_0_SPD_DDRAF_CPU0_R_SCL
J 2
(-6485 5785);
DISPLAY 0.489362 (-6485 5785);
WIRE 16 -1 (-6425 5325)(-6200 5325);
WIRE 16 -1 (-5000 1400)(-5875 1400);
FORCEPROP 2 LAST SIG_NAME I3C_1_SPD_DDRGL_CPU1_SCL
J 0
(-5825 1410);
DISPLAY 0.489362 (-5825 1410);
FORCEPROP 2 LASTPROP $XRERR UNIQUE?
J 0
(-6065 1410);
DISPLAY 0.638298 (-6065 1410);
PAINT MONO (-6065 1410);
DISPLAY INVISIBLE (-6065 1410);
WIRE 16 -1 (-5875 1250)(-5650 1250);
FORCEPROP 2 LAST SIG_NAME I3C_SCM_3_R_SDA
J 0
(-5825 1260);
DISPLAY 0.489362 (-5825 1260);
WIRE 16 -1 (-5650 1250)(-5000 1250);
WIRE 16 -1 (-5650 1625)(-5650 1250);
WIRE 16 -1 (-3650 3075)(-3650 2900);
WIRE 16 -1 (-3650 2900)(-3300 2900);
FORCEPROP 2 LAST SIG_NAME I3C_SPD_DDRAF_CPU1_LVC1_SDA
J 2
(-3525 2910);
DISPLAY 0.489362 (-3525 2910);
FORCEPROP 2 LASTPROP $XRERR UNIQUE?
J 0
(-3765 2910);
DISPLAY 0.638298 (-3765 2910);
PAINT MONO (-3765 2910);
DISPLAY INVISIBLE (-3765 2910);
WIRE 16 -1 (-4450 2900)(-3650 2900);
WIRE 16 -1 (-4450 2950)(-3450 2950);
FORCEPROP 2 LAST SIG_NAME I3C_SPD_DDRAF_CPU1_LVC1_SCL
J 2
(-3525 2960);
DISPLAY 0.489362 (-3525 2960);
FORCEPROP 2 LASTPROP $XRERR UNIQUE?
J 0
(-3765 2960);
DISPLAY 0.638298 (-3765 2960);
PAINT MONO (-3765 2960);
DISPLAY INVISIBLE (-3765 2960);
WIRE 16 -1 (-3450 2950)(-3450 3075);
WIRE 16 -1 (-3450 2950)(-3300 2950);
WIRE 16 -1 (-5950 2700)(-5650 2700);
FORCEPROP 2 LAST SIG_NAME I3C_SCM_2_R_SDA
J 0
(-5910 2710);
DISPLAY 0.489362 (-5910 2710);
WIRE 16 -1 (-5650 2700)(-5050 2700);
WIRE 16 -1 (-5650 3075)(-5650 2700);
WIRE 16 -1 (-5900 2950)(-5050 2950);
FORCEPROP 2 LAST SIG_NAME FM_I3C_CPU1_MUX0_SEL
J 0
(-5710 2960);
DISPLAY 0.489362 (-5710 2960);
WIRE 16 -1 (-5900 3000)(-5050 3000);
FORCEPROP 2 LAST SIG_NAME FM_I3C_CPU1_MUX0_OE_N
J 0
(-5710 3010);
DISPLAY 0.489362 (-5710 3010);
WIRE 16 -1 (-5950 2750)(-5450 2750);
FORCEPROP 2 LAST SIG_NAME I3C_SCM_2_R_SCL
J 0
(-5910 2760);
DISPLAY 0.489362 (-5910 2760);
WIRE 16 -1 (-5450 2750)(-5050 2750);
WIRE 16 -1 (-5450 2750)(-5450 3075);
WIRE 16 -1 (-3650 4600)(-3650 4425);
WIRE 16 -1 (-3650 4425)(-3250 4425);
FORCEPROP 2 LAST SIG_NAME I3C_SPD_DDRGL_CPU0_LVC1_SDA
J 2
(-3525 4435);
DISPLAY 0.489362 (-3525 4435);
FORCEPROP 2 LASTPROP $XRERR UNIQUE?
J 0
(-3765 4435);
DISPLAY 0.638298 (-3765 4435);
PAINT MONO (-3765 4435);
DISPLAY INVISIBLE (-3765 4435);
WIRE 16 -1 (-4450 4425)(-3650 4425);
WIRE 16 -1 (-4450 4475)(-3450 4475);
FORCEPROP 2 LAST SIG_NAME I3C_SPD_DDRGL_CPU0_LVC1_SCL
J 2
(-3525 4485);
DISPLAY 0.489362 (-3525 4485);
FORCEPROP 2 LASTPROP $XRERR UNIQUE?
J 0
(-3765 4485);
DISPLAY 0.638298 (-3765 4485);
PAINT MONO (-3765 4485);
DISPLAY INVISIBLE (-3765 4485);
WIRE 16 -1 (-3450 4475)(-3250 4475);
WIRE 16 -1 (-3450 4475)(-3450 4600);
WIRE 16 -1 (-5050 4375)(-5950 4375);
FORCEPROP 2 LAST SIG_NAME I3C_1_SPD_DDRGL_CPU0_SCL
J 0
(-5900 4385);
DISPLAY 0.489362 (-5900 4385);
FORCEPROP 2 LASTPROP $XRERR UNIQUE?
J 0
(-6140 4385);
DISPLAY 0.638298 (-6140 4385);
PAINT MONO (-6140 4385);
DISPLAY INVISIBLE (-6140 4385);
WIRE 16 -1 (-6000 5325)(-3275 5325);
FORCEPROP 2 LAST SIG_NAME I3C_SPD_DDRAF_CPU0_BYPASS_SCL
J 0
(-5050 5335);
DISPLAY 0.489362 (-5050 5335);
FORCEPROP 2 LASTPROP $XRERR UNIQUE?
J 0
(-5290 5335);
DISPLAY 0.638298 (-5290 5335);
PAINT MONO (-5290 5335);
DISPLAY INVISIBLE (-5290 5335);
WIRE 16 -1 (-3650 6000)(-3650 5825);
WIRE 16 -1 (-3650 5825)(-3250 5825);
FORCEPROP 2 LAST SIG_NAME I3C_SPD_DDRAF_CPU0_LVC1_SDA
J 2
(-3525 5835);
DISPLAY 0.489362 (-3525 5835);
FORCEPROP 2 LASTPROP $XRERR UNIQUE?
J 0
(-3765 5835);
DISPLAY 0.638298 (-3765 5835);
PAINT MONO (-3765 5835);
DISPLAY INVISIBLE (-3765 5835);
WIRE 16 -1 (-4475 5825)(-3650 5825);
WIRE 16 -1 (-4475 5875)(-3450 5875);
FORCEPROP 2 LAST SIG_NAME I3C_SPD_DDRAF_CPU0_LVC1_SCL
J 2
(-3525 5885);
DISPLAY 0.489362 (-3525 5885);
FORCEPROP 2 LASTPROP $XRERR UNIQUE?
J 0
(-3765 5885);
DISPLAY 0.638298 (-3765 5885);
PAINT MONO (-3765 5885);
DISPLAY INVISIBLE (-3765 5885);
WIRE 16 -1 (-3450 5875)(-3250 5875);
WIRE 16 -1 (-3450 5875)(-3450 6000);
WIRE 16 -1 (-5900 4525)(-5050 4525);
FORCEPROP 2 LAST SIG_NAME FM_I3C_CPU0_MUX1_OE_N
J 0
(-5710 4535);
DISPLAY 0.489362 (-5710 4535);
WIRE 16 -1 (-5975 5625)(-5650 5625);
FORCEPROP 2 LAST SIG_NAME I3C_SCM_0_R_SDA
J 0
(-5925 5635);
DISPLAY 0.489362 (-5925 5635);
WIRE 16 -1 (-5075 5625)(-5650 5625);
WIRE 16 -1 (-5650 6075)(-5650 5625);
WIRE 16 -1 (-5975 5675)(-5450 5675);
FORCEPROP 2 LAST SIG_NAME I3C_SCM_0_R_SCL
J 0
(-5925 5685);
DISPLAY 0.489362 (-5925 5685);
WIRE 16 -1 (-5450 5675)(-5075 5675);
WIRE 16 -1 (-5450 5675)(-5450 6075);
WIRE 16 -1 (-5075 5725)(-5975 5725);
FORCEPROP 2 LAST SIG_NAME I3C_0_SPD_DDRAF_CPU0_SDA
J 0
(-5925 5735);
DISPLAY 0.489362 (-5925 5735);
FORCEPROP 2 LASTPROP $XRERR UNIQUE?
J 0
(-6165 5735);
DISPLAY 0.638298 (-6165 5735);
PAINT MONO (-6165 5735);
DISPLAY INVISIBLE (-6165 5735);
WIRE 16 -1 (-5075 5775)(-5975 5775);
FORCEPROP 2 LAST SIG_NAME I3C_0_SPD_DDRAF_CPU0_SCL
J 0
(-5925 5785);
DISPLAY 0.489362 (-5925 5785);
FORCEPROP 2 LASTPROP $XRERR UNIQUE?
J 0
(-6165 5785);
DISPLAY 0.638298 (-6165 5785);
PAINT MONO (-6165 5785);
DISPLAY INVISIBLE (-6165 5785);
WIRE 16 -1 (-5950 4275)(-5450 4275);
FORCEPROP 2 LAST SIG_NAME I3C_SCM_1_R_SCL
J 0
(-5900 4285);
DISPLAY 0.489362 (-5900 4285);
WIRE 16 -1 (-5450 4275)(-5050 4275);
WIRE 16 -1 (-5450 4275)(-5450 4600);
WIRE 16 -1 (-5950 4225)(-5650 4225);
FORCEPROP 2 LAST SIG_NAME I3C_SCM_1_R_SDA
J 0
(-5900 4235);
DISPLAY 0.489362 (-5900 4235);
WIRE 16 -1 (-5650 4225)(-5050 4225);
WIRE 16 -1 (-5650 4600)(-5650 4225);
WIRE 16 -1 (-5875 1300)(-5450 1300);
FORCEPROP 2 LAST SIG_NAME I3C_SCM_3_R_SCL
J 0
(-5825 1310);
DISPLAY 0.489362 (-5825 1310);
WIRE 16 -1 (-5450 1300)(-5000 1300);
WIRE 16 -1 (-5450 1300)(-5450 1625);
WIRE 16 -1 (-4400 1500)(-3450 1500);
FORCEPROP 2 LAST SIG_NAME I3C_SPD_DDRGL_CPU1_LVC1_SCL
J 2
(-3500 1510);
DISPLAY 0.489362 (-3500 1510);
FORCEPROP 2 LASTPROP $XRERR UNIQUE?
J 0
(-3740 1510);
DISPLAY 0.638298 (-3740 1510);
PAINT MONO (-3740 1510);
DISPLAY INVISIBLE (-3740 1510);
WIRE 16 -1 (-3450 1500)(-3450 1625);
WIRE 16 -1 (-3450 1500)(-3275 1500);
WIRE 16 -1 (-3650 1625)(-3650 1450);
WIRE 16 -1 (-3650 1450)(-3275 1450);
FORCEPROP 2 LAST SIG_NAME I3C_SPD_DDRGL_CPU1_LVC1_SDA
J 2
(-3500 1460);
DISPLAY 0.489362 (-3500 1460);
FORCEPROP 2 LASTPROP $XRERR UNIQUE?
J 0
(-3740 1460);
DISPLAY 0.638298 (-3740 1460);
PAINT MONO (-3740 1460);
DISPLAY INVISIBLE (-3740 1460);
WIRE 16 -1 (-4400 1450)(-3650 1450);
WIRE 16 -1 (-5050 4325)(-5950 4325);
FORCEPROP 2 LAST SIG_NAME I3C_1_SPD_DDRGL_CPU0_SDA
J 0
(-5900 4335);
DISPLAY 0.489362 (-5900 4335);
FORCEPROP 2 LASTPROP $XRERR UNIQUE?
J 0
(-6140 4335);
DISPLAY 0.638298 (-6140 4335);
PAINT MONO (-6140 4335);
DISPLAY INVISIBLE (-6140 4335);
WIRE 16 -1 (-5000 1350)(-5875 1350);
FORCEPROP 2 LAST SIG_NAME I3C_1_SPD_DDRGL_CPU1_SDA
J 0
(-5825 1360);
DISPLAY 0.489362 (-5825 1360);
FORCEPROP 2 LASTPROP $XRERR UNIQUE?
J 0
(-6065 1360);
DISPLAY 0.638298 (-6065 1360);
PAINT MONO (-6065 1360);
DISPLAY INVISIBLE (-6065 1360);
WIRE 16 -1 (-5050 2850)(-5950 2850);
FORCEPROP 2 LAST SIG_NAME I3C_0_SPD_DDRAF_CPU1_SCL
J 0
(-5910 2860);
DISPLAY 0.489362 (-5910 2860);
FORCEPROP 2 LASTPROP $XRERR UNIQUE?
J 0
(-6150 2860);
DISPLAY 0.638298 (-6150 2860);
PAINT MONO (-6150 2860);
DISPLAY INVISIBLE (-6150 2860);
WIRE 16 -1 (-5050 2800)(-5950 2800);
FORCEPROP 2 LAST SIG_NAME I3C_0_SPD_DDRAF_CPU1_SDA
J 0
(-5910 2810);
DISPLAY 0.489362 (-5910 2810);
FORCEPROP 2 LASTPROP $XRERR UNIQUE?
J 0
(-6150 2810);
DISPLAY 0.638298 (-6150 2810);
PAINT MONO (-6150 2810);
DISPLAY INVISIBLE (-6150 2810);
WIRE 16 -1 (-5925 5925)(-5075 5925);
FORCEPROP 2 LAST SIG_NAME FM_I3C_CPU0_MUX0_OE_N
J 0
(-5735 5935);
DISPLAY 0.489362 (-5735 5935);
WIRE 16 -1 (-5925 5875)(-5075 5875);
FORCEPROP 2 LAST SIG_NAME FM_I3C_CPU0_MUX0_SEL
J 0
(-5735 5885);
DISPLAY 0.489362 (-5735 5885);
WIRE 16 -1 (-5850 1500)(-5000 1500);
FORCEPROP 2 LAST SIG_NAME FM_I3C_CPU1_MUX1_SEL
J 0
(-5660 1510);
DISPLAY 0.489362 (-5660 1510);
WIRE 16 -1 (-5900 4475)(-5050 4475);
FORCEPROP 2 LAST SIG_NAME FM_I3C_CPU0_MUX1_SEL
J 0
(-5710 4485);
DISPLAY 0.489362 (-5710 4485);
DOT 1 (-3450 3350);
DOT 1 (-3450 5875);
DOT 1 (-2900 5875);
DOT 1 (-3450 6275);
DOT 1 (-3650 5825);
DOT 1 (-6375 2800);
DOT 1 (-5450 1300);
DOT 1 (-5450 1850);
DOT 1 (-5650 2700);
DOT 1 (-5450 2750);
DOT 1 (-5450 4825);
DOT 1 (-5450 4275);
DOT 1 (-5650 4225);
DOT 1 (-5450 6375);
DOT 1 (-5650 5625);
DOT 1 (-5450 5675);
DOT 1 (-3450 2950);
DOT 1 (-3650 1450);
DOT 1 (-3450 1500);
DOT 1 (-3650 2900);
DOT 1 (-3450 4475);
DOT 1 (-3650 4425);
DOT 1 (-3450 4875);
DOT 1 (-4350 6375);
DOT 1 (-6475 5725);
DOT 1 (-2825 5825);
DOT 1 (-2775 4425);
DOT 1 (-2850 4475);
DOT 1 (-2800 2950);
DOT 1 (-2675 1450);
DOT 1 (-2750 1500);
DOT 1 (-6375 4375);
DOT 1 (-4275 2000);
DOT 1 (-6325 1350);
DOT 1 (-6425 5775);
DOT 1 (-6275 1400);
DOT 1 (-4325 4975);
DOT 1 (-4325 3450);
DOT 1 (-5450 3300);
DOT 1 (-3450 1900);
DOT 1 (-6425 4325);
DOT 1 (-6325 2850);
DOT 1 (-2725 2900);
DOT 1 (-5650 1250);
FORCENOTE
$CDS_IMAGE|12312312.jpg|1924|507
(-8150 675) 0;
DISPLAY LEFT (-8150 675);
QUIT
